FILE_TYPE = MACRO_DRAWING;
SET COLOR_WIRE YELLOW;
SET COLOR_PROP ORANGE;
SET COLOR_DOT WHITE;
SET COLOR_ARC YELLOW;
SET COLOR_BODY GREEN;
SET COLOR_NOTE PURPLE;
SET PROP_DISPLAY VALUE;
SET PAGE_NUMBER P63;
FORCEADD OFFPAGE..1
(-6750 6025);
FORCEPROP 2 LAST CDS_LIB standard
J 0
(-6750 6025);
DISPLAY INVISIBLE (-6750 6025);
FORCEPROP 2 LAST PATH I1
J 0
(-6700 6100);
DISPLAY 0.680851 (-6700 6100);
DISPLAY INVISIBLE (-6700 6100);
FORCEPROP 1 LAST OFFPAGE TRUE
J 0
(-6425 5900);
DISPLAY 0.872340 (-6425 5900);
PAINT GREEN (-6425 5900);
DISPLAY INVISIBLE (-6425 5900);
FORCEPROP 1 LAST COMMENT_BODY TRUE
J 0
(-6625 5925);
DISPLAY 0.872340 (-6625 5925);
PAINT GREEN (-6625 5925);
DISPLAY INVISIBLE (-6625 5925);
FORCEADD TAP..6
(-5650 4600);
FORCEPROP 3 LASTPIN (-5600 4600) SIG_NAME P5E_CPU0_P0_TX_DP<12>
J 0
(-5590 4610);
DISPLAY 0.659574 (-5590 4610);
PAINT MONO (-5590 4610);
DISPLAY INVISIBLE (-5590 4610);
FORCEPROP 1 LASTPIN (-5600 4600) BN 12
J 0
(-5652 4608);
DISPLAY 0.680851 (-5652 4608);
PAINT MONO (-5652 4608);
FORCEPROP 2 LAST CDS_LIB standard
J 0
(-5650 4600);
DISPLAY INVISIBLE (-5650 4600);
FORCEPROP 1 LAST PATH I10
J 0
(-5652 4600);
DISPLAY 0.872340 (-5652 4600);
PAINT GREEN (-5652 4600);
DISPLAY INVISIBLE (-5652 4600);
FORCEPROP 1 LAST BODY_TYPE PLUMBING
J 0
(-5650 4550);
DISPLAY 0.574468 (-5650 4550);
PAINT GREEN (-5650 4550);
DISPLAY INVISIBLE (-5650 4550);
FORCEPROP 1 LAST HDL_TAP TRUE
J 0
(-5325 4475);
DISPLAY 0.574468 (-5325 4475);
PAINT GREEN (-5325 4475);
DISPLAY INVISIBLE (-5325 4475);
FORCEADD OFFPAGE..1
(-6750 5975);
FORCEPROP 2 LAST CDS_LIB standard
J 0
(-6750 5975);
DISPLAY INVISIBLE (-6750 5975);
FORCEPROP 2 LAST PATH I100
J 0
(-6700 6050);
DISPLAY 0.680851 (-6700 6050);
DISPLAY INVISIBLE (-6700 6050);
FORCEPROP 1 LAST OFFPAGE TRUE
J 0
(-6425 5850);
DISPLAY 0.872340 (-6425 5850);
PAINT GREEN (-6425 5850);
DISPLAY INVISIBLE (-6425 5850);
FORCEPROP 1 LAST COMMENT_BODY TRUE
J 0
(-6625 5875);
DISPLAY 0.872340 (-6625 5875);
PAINT GREEN (-6625 5875);
DISPLAY INVISIBLE (-6625 5875);
FORCEADD OFFPAGE..2
(-2800 3475);
FORCEPROP 1 LAST COMMENT_BODY TRUE
J 0
(-2845 3380);
DISPLAY 0.872340 (-2845 3380);
PAINT GREEN (-2845 3380);
DISPLAY INVISIBLE (-2845 3380);
FORCEPROP 1 LAST OFFPAGE TRUE
J 0
(-2475 3350);
DISPLAY 0.872340 (-2475 3350);
PAINT GREEN (-2475 3350);
DISPLAY INVISIBLE (-2475 3350);
FORCEPROP 2 LAST PATH I101
J 0
(-2625 3550);
DISPLAY 0.680851 (-2625 3550);
DISPLAY INVISIBLE (-2625 3550);
FORCEPROP 2 LAST CDS_LIB standard
J 0
(-2800 3475);
DISPLAY INVISIBLE (-2800 3475);
FORCEADD OFFPAGE..2
(-2800 3525);
FORCEPROP 1 LAST COMMENT_BODY TRUE
J 0
(-2845 3430);
DISPLAY 0.872340 (-2845 3430);
PAINT GREEN (-2845 3430);
DISPLAY INVISIBLE (-2845 3430);
FORCEPROP 1 LAST OFFPAGE TRUE
J 0
(-2475 3400);
DISPLAY 0.872340 (-2475 3400);
PAINT GREEN (-2475 3400);
DISPLAY INVISIBLE (-2475 3400);
FORCEPROP 2 LAST PATH I102
J 0
(-2625 3600);
DISPLAY 0.680851 (-2625 3600);
DISPLAY INVISIBLE (-2625 3600);
FORCEPROP 2 LAST CDS_LIB standard
J 0
(-2800 3525);
DISPLAY INVISIBLE (-2800 3525);
FORCEADD TAP..6
R 2
(-3775 3150);
FORCEPROP 3 LASTPIN (-3825 3150) SIG_NAME P5E_CPU0_P1_TX_C_DN<1>
J 0
(-3815 3160);
DISPLAY 0.659574 (-3815 3160);
PAINT MONO (-3815 3160);
DISPLAY INVISIBLE (-3815 3160);
FORCEPROP 1 LASTPIN (-3825 3150) BN 1
J 2
(-3773 3158);
DISPLAY 0.680851 (-3773 3158);
PAINT MONO (-3773 3158);
FORCEPROP 2 LAST BOM_COST IO_SLOT
J 0
(-4275 3250);
DISPLAY 0.829787 (-4275 3250);
DISPLAY INVISIBLE (-4275 3250);
FORCEPROP 1 LAST BODY_TYPE PLUMBING
J 2
(-3775 3100);
DISPLAY 0.702128 (-3775 3100);
PAINT GREEN (-3775 3100);
DISPLAY INVISIBLE (-3775 3100);
FORCEPROP 1 LAST HDL_TAP TRUE
J 2
(-4100 3025);
DISPLAY 0.702128 (-4100 3025);
PAINT GREEN (-4100 3025);
DISPLAY INVISIBLE (-4100 3025);
FORCEPROP 2 LAST ROOM RISER1
J 0
(-4275 3200);
DISPLAY 0.829787 (-4275 3200);
PAINT RED (-4275 3200);
DISPLAY INVISIBLE (-4275 3200);
FORCEPROP 1 LAST PATH I103
J 2
(-3773 3150);
DISPLAY 0.872340 (-3773 3150);
PAINT GREEN (-3773 3150);
DISPLAY INVISIBLE (-3773 3150);
FORCEPROP 2 LAST CDS_LIB standard
J 0
(-3775 3150);
DISPLAY INVISIBLE (-3775 3150);
FORCEADD TAP..6
R 2
(-3775 3250);
FORCEPROP 3 LASTPIN (-3825 3250) SIG_NAME P5E_CPU0_P1_TX_C_DN<0>
J 0
(-3815 3260);
DISPLAY 0.659574 (-3815 3260);
PAINT MONO (-3815 3260);
DISPLAY INVISIBLE (-3815 3260);
FORCEPROP 1 LASTPIN (-3825 3250) BN 0
J 2
(-3773 3258);
DISPLAY 0.680851 (-3773 3258);
PAINT MONO (-3773 3258);
FORCEPROP 2 LAST BOM_COST IO_SLOT
J 0
(-4275 3350);
DISPLAY 0.829787 (-4275 3350);
DISPLAY INVISIBLE (-4275 3350);
FORCEPROP 1 LAST BODY_TYPE PLUMBING
J 2
(-3775 3200);
DISPLAY 0.702128 (-3775 3200);
PAINT GREEN (-3775 3200);
DISPLAY INVISIBLE (-3775 3200);
FORCEPROP 1 LAST HDL_TAP TRUE
J 2
(-4100 3125);
DISPLAY 0.702128 (-4100 3125);
PAINT GREEN (-4100 3125);
DISPLAY INVISIBLE (-4100 3125);
FORCEPROP 2 LAST ROOM RISER1
J 0
(-4275 3300);
DISPLAY 0.829787 (-4275 3300);
PAINT RED (-4275 3300);
DISPLAY INVISIBLE (-4275 3300);
FORCEPROP 1 LAST PATH I104
J 2
(-3773 3250);
DISPLAY 0.872340 (-3773 3250);
PAINT GREEN (-3773 3250);
DISPLAY INVISIBLE (-3773 3250);
FORCEPROP 2 LAST CDS_LIB standard
J 0
(-3775 3250);
DISPLAY INVISIBLE (-3775 3250);
FORCEADD TAP..6
R 2
(-3925 3200);
FORCEPROP 3 LASTPIN (-3975 3200) SIG_NAME P5E_CPU0_P1_TX_C_DP<1>
J 0
(-3965 3210);
DISPLAY 0.659574 (-3965 3210);
PAINT MONO (-3965 3210);
DISPLAY INVISIBLE (-3965 3210);
FORCEPROP 1 LASTPIN (-3975 3200) BN 1
J 2
(-3923 3208);
DISPLAY 0.680851 (-3923 3208);
PAINT MONO (-3923 3208);
FORCEPROP 2 LAST BOM_COST IO_SLOT
J 0
(-4425 3300);
DISPLAY 0.829787 (-4425 3300);
DISPLAY INVISIBLE (-4425 3300);
FORCEPROP 1 LAST BODY_TYPE PLUMBING
J 2
(-3925 3150);
DISPLAY 0.702128 (-3925 3150);
PAINT GREEN (-3925 3150);
DISPLAY INVISIBLE (-3925 3150);
FORCEPROP 1 LAST HDL_TAP TRUE
J 2
(-4250 3075);
DISPLAY 0.702128 (-4250 3075);
PAINT GREEN (-4250 3075);
DISPLAY INVISIBLE (-4250 3075);
FORCEPROP 2 LAST ROOM RISER1
J 0
(-4425 3250);
DISPLAY 0.829787 (-4425 3250);
PAINT RED (-4425 3250);
DISPLAY INVISIBLE (-4425 3250);
FORCEPROP 1 LAST PATH I105
J 2
(-3923 3200);
DISPLAY 0.872340 (-3923 3200);
PAINT GREEN (-3923 3200);
DISPLAY INVISIBLE (-3923 3200);
FORCEPROP 2 LAST CDS_LIB standard
J 0
(-3925 3200);
DISPLAY INVISIBLE (-3925 3200);
FORCEADD TAP..6
R 2
(-3925 3300);
FORCEPROP 3 LASTPIN (-3975 3300) SIG_NAME P5E_CPU0_P1_TX_C_DP<0>
J 0
(-3965 3310);
DISPLAY 0.659574 (-3965 3310);
PAINT MONO (-3965 3310);
DISPLAY INVISIBLE (-3965 3310);
FORCEPROP 1 LASTPIN (-3975 3300) BN 0
J 2
(-3923 3308);
DISPLAY 0.680851 (-3923 3308);
PAINT MONO (-3923 3308);
FORCEPROP 2 LAST BOM_COST IO_SLOT
J 0
(-4425 3400);
DISPLAY 0.829787 (-4425 3400);
DISPLAY INVISIBLE (-4425 3400);
FORCEPROP 1 LAST BODY_TYPE PLUMBING
J 2
(-3925 3250);
DISPLAY 0.702128 (-3925 3250);
PAINT GREEN (-3925 3250);
DISPLAY INVISIBLE (-3925 3250);
FORCEPROP 1 LAST HDL_TAP TRUE
J 2
(-4250 3175);
DISPLAY 0.702128 (-4250 3175);
PAINT GREEN (-4250 3175);
DISPLAY INVISIBLE (-4250 3175);
FORCEPROP 2 LAST ROOM RISER1
J 0
(-4425 3350);
DISPLAY 0.829787 (-4425 3350);
PAINT RED (-4425 3350);
DISPLAY INVISIBLE (-4425 3350);
FORCEPROP 1 LAST PATH I106
J 2
(-3923 3300);
DISPLAY 0.872340 (-3923 3300);
PAINT GREEN (-3923 3300);
DISPLAY INVISIBLE (-3923 3300);
FORCEPROP 2 LAST CDS_LIB standard
J 0
(-3925 3300);
DISPLAY INVISIBLE (-3925 3300);
FORCEADD TAP..6
R 2
(-3775 3050);
FORCEPROP 3 LASTPIN (-3825 3050) SIG_NAME P5E_CPU0_P1_TX_C_DN<2>
J 0
(-3815 3060);
DISPLAY 0.659574 (-3815 3060);
PAINT MONO (-3815 3060);
DISPLAY INVISIBLE (-3815 3060);
FORCEPROP 1 LASTPIN (-3825 3050) BN 2
J 2
(-3773 3058);
DISPLAY 0.680851 (-3773 3058);
PAINT MONO (-3773 3058);
FORCEPROP 2 LAST BOM_COST IO_SLOT
J 0
(-4275 3150);
DISPLAY 0.829787 (-4275 3150);
DISPLAY INVISIBLE (-4275 3150);
FORCEPROP 1 LAST BODY_TYPE PLUMBING
J 2
(-3775 3000);
DISPLAY 0.702128 (-3775 3000);
PAINT GREEN (-3775 3000);
DISPLAY INVISIBLE (-3775 3000);
FORCEPROP 1 LAST HDL_TAP TRUE
J 2
(-4100 2925);
DISPLAY 0.702128 (-4100 2925);
PAINT GREEN (-4100 2925);
DISPLAY INVISIBLE (-4100 2925);
FORCEPROP 2 LAST ROOM RISER1
J 0
(-4275 3100);
DISPLAY 0.829787 (-4275 3100);
PAINT RED (-4275 3100);
DISPLAY INVISIBLE (-4275 3100);
FORCEPROP 1 LAST PATH I107
J 2
(-3773 3050);
DISPLAY 0.872340 (-3773 3050);
PAINT GREEN (-3773 3050);
DISPLAY INVISIBLE (-3773 3050);
FORCEPROP 2 LAST CDS_LIB standard
J 0
(-3775 3050);
DISPLAY INVISIBLE (-3775 3050);
FORCEADD TAP..6
R 2
(-3775 2950);
FORCEPROP 3 LASTPIN (-3825 2950) SIG_NAME P5E_CPU0_P1_TX_C_DN<3>
J 0
(-3815 2960);
DISPLAY 0.659574 (-3815 2960);
PAINT MONO (-3815 2960);
DISPLAY INVISIBLE (-3815 2960);
FORCEPROP 1 LASTPIN (-3825 2950) BN 3
J 2
(-3773 2958);
DISPLAY 0.680851 (-3773 2958);
PAINT MONO (-3773 2958);
FORCEPROP 2 LAST BOM_COST IO_SLOT
J 0
(-4275 3050);
DISPLAY 0.829787 (-4275 3050);
DISPLAY INVISIBLE (-4275 3050);
FORCEPROP 1 LAST BODY_TYPE PLUMBING
J 2
(-3775 2900);
DISPLAY 0.702128 (-3775 2900);
PAINT GREEN (-3775 2900);
DISPLAY INVISIBLE (-3775 2900);
FORCEPROP 1 LAST HDL_TAP TRUE
J 2
(-4100 2825);
DISPLAY 0.702128 (-4100 2825);
PAINT GREEN (-4100 2825);
DISPLAY INVISIBLE (-4100 2825);
FORCEPROP 2 LAST ROOM RISER1
J 0
(-4275 3000);
DISPLAY 0.829787 (-4275 3000);
PAINT RED (-4275 3000);
DISPLAY INVISIBLE (-4275 3000);
FORCEPROP 1 LAST PATH I108
J 2
(-3773 2950);
DISPLAY 0.872340 (-3773 2950);
PAINT GREEN (-3773 2950);
DISPLAY INVISIBLE (-3773 2950);
FORCEPROP 2 LAST CDS_LIB standard
J 0
(-3775 2950);
DISPLAY INVISIBLE (-3775 2950);
FORCEADD TAP..6
R 2
(-3775 2850);
FORCEPROP 3 LASTPIN (-3825 2850) SIG_NAME P5E_CPU0_P1_TX_C_DN<4>
J 0
(-3815 2860);
DISPLAY 0.659574 (-3815 2860);
PAINT MONO (-3815 2860);
DISPLAY INVISIBLE (-3815 2860);
FORCEPROP 1 LASTPIN (-3825 2850) BN 4
J 2
(-3773 2858);
DISPLAY 0.680851 (-3773 2858);
PAINT MONO (-3773 2858);
FORCEPROP 2 LAST BOM_COST IO_SLOT
J 0
(-4275 2950);
DISPLAY 0.829787 (-4275 2950);
DISPLAY INVISIBLE (-4275 2950);
FORCEPROP 1 LAST BODY_TYPE PLUMBING
J 2
(-3775 2800);
DISPLAY 0.702128 (-3775 2800);
PAINT GREEN (-3775 2800);
DISPLAY INVISIBLE (-3775 2800);
FORCEPROP 1 LAST HDL_TAP TRUE
J 2
(-4100 2725);
DISPLAY 0.702128 (-4100 2725);
PAINT GREEN (-4100 2725);
DISPLAY INVISIBLE (-4100 2725);
FORCEPROP 2 LAST ROOM RISER1
J 0
(-4275 2900);
DISPLAY 0.829787 (-4275 2900);
PAINT RED (-4275 2900);
DISPLAY INVISIBLE (-4275 2900);
FORCEPROP 1 LAST PATH I109
J 2
(-3773 2850);
DISPLAY 0.872340 (-3773 2850);
PAINT GREEN (-3773 2850);
DISPLAY INVISIBLE (-3773 2850);
FORCEPROP 2 LAST CDS_LIB standard
J 0
(-3775 2850);
DISPLAY INVISIBLE (-3775 2850);
FORCEADD TAP..6
(-5800 4750);
FORCEPROP 3 LASTPIN (-5750 4750) SIG_NAME P5E_CPU0_P0_TX_DN<10>
J 0
(-5740 4760);
DISPLAY 0.659574 (-5740 4760);
PAINT MONO (-5740 4760);
DISPLAY INVISIBLE (-5740 4760);
FORCEPROP 1 LASTPIN (-5750 4750) BN 10
J 0
(-5802 4758);
DISPLAY 0.680851 (-5802 4758);
PAINT MONO (-5802 4758);
FORCEPROP 2 LAST CDS_LIB standard
J 0
(-5800 4750);
DISPLAY INVISIBLE (-5800 4750);
FORCEPROP 1 LAST PATH I11
J 0
(-5802 4750);
DISPLAY 0.872340 (-5802 4750);
PAINT GREEN (-5802 4750);
DISPLAY INVISIBLE (-5802 4750);
FORCEPROP 1 LAST BODY_TYPE PLUMBING
J 0
(-5800 4700);
DISPLAY 0.574468 (-5800 4700);
PAINT GREEN (-5800 4700);
DISPLAY INVISIBLE (-5800 4700);
FORCEPROP 1 LAST HDL_TAP TRUE
J 0
(-5475 4625);
DISPLAY 0.574468 (-5475 4625);
PAINT GREEN (-5475 4625);
DISPLAY INVISIBLE (-5475 4625);
FORCEADD TAP..6
R 2
(-3775 2750);
FORCEPROP 3 LASTPIN (-3825 2750) SIG_NAME P5E_CPU0_P1_TX_C_DN<5>
J 0
(-3815 2760);
DISPLAY 0.659574 (-3815 2760);
PAINT MONO (-3815 2760);
DISPLAY INVISIBLE (-3815 2760);
FORCEPROP 1 LASTPIN (-3825 2750) BN 5
J 2
(-3773 2758);
DISPLAY 0.680851 (-3773 2758);
PAINT MONO (-3773 2758);
FORCEPROP 2 LAST BOM_COST IO_SLOT
J 0
(-4275 2850);
DISPLAY 0.829787 (-4275 2850);
DISPLAY INVISIBLE (-4275 2850);
FORCEPROP 1 LAST BODY_TYPE PLUMBING
J 2
(-3775 2700);
DISPLAY 0.702128 (-3775 2700);
PAINT GREEN (-3775 2700);
DISPLAY INVISIBLE (-3775 2700);
FORCEPROP 1 LAST HDL_TAP TRUE
J 2
(-4100 2625);
DISPLAY 0.702128 (-4100 2625);
PAINT GREEN (-4100 2625);
DISPLAY INVISIBLE (-4100 2625);
FORCEPROP 2 LAST ROOM RISER1
J 0
(-4275 2800);
DISPLAY 0.829787 (-4275 2800);
PAINT RED (-4275 2800);
DISPLAY INVISIBLE (-4275 2800);
FORCEPROP 1 LAST PATH I110
J 2
(-3773 2750);
DISPLAY 0.872340 (-3773 2750);
PAINT GREEN (-3773 2750);
DISPLAY INVISIBLE (-3773 2750);
FORCEPROP 2 LAST CDS_LIB standard
J 0
(-3775 2750);
DISPLAY INVISIBLE (-3775 2750);
FORCEADD TAP..6
R 2
(-3775 2650);
FORCEPROP 3 LASTPIN (-3825 2650) SIG_NAME P5E_CPU0_P1_TX_C_DN<6>
J 0
(-3815 2660);
DISPLAY 0.659574 (-3815 2660);
PAINT MONO (-3815 2660);
DISPLAY INVISIBLE (-3815 2660);
FORCEPROP 1 LASTPIN (-3825 2650) BN 6
J 2
(-3773 2658);
DISPLAY 0.680851 (-3773 2658);
PAINT MONO (-3773 2658);
FORCEPROP 2 LAST BOM_COST IO_SLOT
J 0
(-4275 2750);
DISPLAY 0.829787 (-4275 2750);
DISPLAY INVISIBLE (-4275 2750);
FORCEPROP 1 LAST BODY_TYPE PLUMBING
J 2
(-3775 2600);
DISPLAY 0.702128 (-3775 2600);
PAINT GREEN (-3775 2600);
DISPLAY INVISIBLE (-3775 2600);
FORCEPROP 1 LAST HDL_TAP TRUE
J 2
(-4100 2525);
DISPLAY 0.702128 (-4100 2525);
PAINT GREEN (-4100 2525);
DISPLAY INVISIBLE (-4100 2525);
FORCEPROP 2 LAST ROOM RISER1
J 0
(-4275 2700);
DISPLAY 0.829787 (-4275 2700);
PAINT RED (-4275 2700);
DISPLAY INVISIBLE (-4275 2700);
FORCEPROP 1 LAST PATH I111
J 2
(-3773 2650);
DISPLAY 0.872340 (-3773 2650);
PAINT GREEN (-3773 2650);
DISPLAY INVISIBLE (-3773 2650);
FORCEPROP 2 LAST CDS_LIB standard
J 0
(-3775 2650);
DISPLAY INVISIBLE (-3775 2650);
FORCEADD TAP..6
R 2
(-3925 3000);
FORCEPROP 3 LASTPIN (-3975 3000) SIG_NAME P5E_CPU0_P1_TX_C_DP<3>
J 0
(-3965 3010);
DISPLAY 0.659574 (-3965 3010);
PAINT MONO (-3965 3010);
DISPLAY INVISIBLE (-3965 3010);
FORCEPROP 1 LASTPIN (-3975 3000) BN 3
J 2
(-3923 3008);
DISPLAY 0.680851 (-3923 3008);
PAINT MONO (-3923 3008);
FORCEPROP 2 LAST BOM_COST IO_SLOT
J 0
(-4425 3100);
DISPLAY 0.829787 (-4425 3100);
DISPLAY INVISIBLE (-4425 3100);
FORCEPROP 1 LAST BODY_TYPE PLUMBING
J 2
(-3925 2950);
DISPLAY 0.702128 (-3925 2950);
PAINT GREEN (-3925 2950);
DISPLAY INVISIBLE (-3925 2950);
FORCEPROP 1 LAST HDL_TAP TRUE
J 2
(-4250 2875);
DISPLAY 0.702128 (-4250 2875);
PAINT GREEN (-4250 2875);
DISPLAY INVISIBLE (-4250 2875);
FORCEPROP 2 LAST ROOM RISER1
J 0
(-4425 3050);
DISPLAY 0.829787 (-4425 3050);
PAINT RED (-4425 3050);
DISPLAY INVISIBLE (-4425 3050);
FORCEPROP 1 LAST PATH I112
J 2
(-3923 3000);
DISPLAY 0.872340 (-3923 3000);
PAINT GREEN (-3923 3000);
DISPLAY INVISIBLE (-3923 3000);
FORCEPROP 2 LAST CDS_LIB standard
J 0
(-3925 3000);
DISPLAY INVISIBLE (-3925 3000);
FORCEADD TAP..6
R 2
(-3925 3100);
FORCEPROP 3 LASTPIN (-3975 3100) SIG_NAME P5E_CPU0_P1_TX_C_DP<2>
J 0
(-3965 3110);
DISPLAY 0.659574 (-3965 3110);
PAINT MONO (-3965 3110);
DISPLAY INVISIBLE (-3965 3110);
FORCEPROP 1 LASTPIN (-3975 3100) BN 2
J 2
(-3923 3108);
DISPLAY 0.680851 (-3923 3108);
PAINT MONO (-3923 3108);
FORCEPROP 2 LAST BOM_COST IO_SLOT
J 0
(-4425 3200);
DISPLAY 0.829787 (-4425 3200);
DISPLAY INVISIBLE (-4425 3200);
FORCEPROP 1 LAST BODY_TYPE PLUMBING
J 2
(-3925 3050);
DISPLAY 0.702128 (-3925 3050);
PAINT GREEN (-3925 3050);
DISPLAY INVISIBLE (-3925 3050);
FORCEPROP 1 LAST HDL_TAP TRUE
J 2
(-4250 2975);
DISPLAY 0.702128 (-4250 2975);
PAINT GREEN (-4250 2975);
DISPLAY INVISIBLE (-4250 2975);
FORCEPROP 2 LAST ROOM RISER1
J 0
(-4425 3150);
DISPLAY 0.829787 (-4425 3150);
PAINT RED (-4425 3150);
DISPLAY INVISIBLE (-4425 3150);
FORCEPROP 1 LAST PATH I113
J 2
(-3923 3100);
DISPLAY 0.872340 (-3923 3100);
PAINT GREEN (-3923 3100);
DISPLAY INVISIBLE (-3923 3100);
FORCEPROP 2 LAST CDS_LIB standard
J 0
(-3925 3100);
DISPLAY INVISIBLE (-3925 3100);
FORCEADD TAP..6
R 2
(-3925 2900);
FORCEPROP 3 LASTPIN (-3975 2900) SIG_NAME P5E_CPU0_P1_TX_C_DP<4>
J 0
(-3965 2910);
DISPLAY 0.659574 (-3965 2910);
PAINT MONO (-3965 2910);
DISPLAY INVISIBLE (-3965 2910);
FORCEPROP 1 LASTPIN (-3975 2900) BN 4
J 2
(-3923 2908);
DISPLAY 0.680851 (-3923 2908);
PAINT MONO (-3923 2908);
FORCEPROP 2 LAST BOM_COST IO_SLOT
J 0
(-4425 3000);
DISPLAY 0.829787 (-4425 3000);
DISPLAY INVISIBLE (-4425 3000);
FORCEPROP 1 LAST BODY_TYPE PLUMBING
J 2
(-3925 2850);
DISPLAY 0.702128 (-3925 2850);
PAINT GREEN (-3925 2850);
DISPLAY INVISIBLE (-3925 2850);
FORCEPROP 1 LAST HDL_TAP TRUE
J 2
(-4250 2775);
DISPLAY 0.702128 (-4250 2775);
PAINT GREEN (-4250 2775);
DISPLAY INVISIBLE (-4250 2775);
FORCEPROP 2 LAST ROOM RISER1
J 0
(-4425 2950);
DISPLAY 0.829787 (-4425 2950);
PAINT RED (-4425 2950);
DISPLAY INVISIBLE (-4425 2950);
FORCEPROP 1 LAST PATH I114
J 2
(-3923 2900);
DISPLAY 0.872340 (-3923 2900);
PAINT GREEN (-3923 2900);
DISPLAY INVISIBLE (-3923 2900);
FORCEPROP 2 LAST CDS_LIB standard
J 0
(-3925 2900);
DISPLAY INVISIBLE (-3925 2900);
FORCEADD TAP..6
R 2
(-3925 2800);
FORCEPROP 3 LASTPIN (-3975 2800) SIG_NAME P5E_CPU0_P1_TX_C_DP<5>
J 0
(-3965 2810);
DISPLAY 0.659574 (-3965 2810);
PAINT MONO (-3965 2810);
DISPLAY INVISIBLE (-3965 2810);
FORCEPROP 1 LASTPIN (-3975 2800) BN 5
J 2
(-3923 2808);
DISPLAY 0.680851 (-3923 2808);
PAINT MONO (-3923 2808);
FORCEPROP 2 LAST BOM_COST IO_SLOT
J 0
(-4425 2900);
DISPLAY 0.829787 (-4425 2900);
DISPLAY INVISIBLE (-4425 2900);
FORCEPROP 1 LAST BODY_TYPE PLUMBING
J 2
(-3925 2750);
DISPLAY 0.702128 (-3925 2750);
PAINT GREEN (-3925 2750);
DISPLAY INVISIBLE (-3925 2750);
FORCEPROP 1 LAST HDL_TAP TRUE
J 2
(-4250 2675);
DISPLAY 0.702128 (-4250 2675);
PAINT GREEN (-4250 2675);
DISPLAY INVISIBLE (-4250 2675);
FORCEPROP 2 LAST ROOM RISER1
J 0
(-4425 2850);
DISPLAY 0.829787 (-4425 2850);
PAINT RED (-4425 2850);
DISPLAY INVISIBLE (-4425 2850);
FORCEPROP 1 LAST PATH I115
J 2
(-3923 2800);
DISPLAY 0.872340 (-3923 2800);
PAINT GREEN (-3923 2800);
DISPLAY INVISIBLE (-3923 2800);
FORCEPROP 2 LAST CDS_LIB standard
J 0
(-3925 2800);
DISPLAY INVISIBLE (-3925 2800);
FORCEADD TAP..6
R 2
(-3925 2700);
FORCEPROP 3 LASTPIN (-3975 2700) SIG_NAME P5E_CPU0_P1_TX_C_DP<6>
J 0
(-3965 2710);
DISPLAY 0.659574 (-3965 2710);
PAINT MONO (-3965 2710);
DISPLAY INVISIBLE (-3965 2710);
FORCEPROP 1 LASTPIN (-3975 2700) BN 6
J 2
(-3923 2708);
DISPLAY 0.680851 (-3923 2708);
PAINT MONO (-3923 2708);
FORCEPROP 2 LAST BOM_COST IO_SLOT
J 0
(-4425 2800);
DISPLAY 0.829787 (-4425 2800);
DISPLAY INVISIBLE (-4425 2800);
FORCEPROP 1 LAST BODY_TYPE PLUMBING
J 2
(-3925 2650);
DISPLAY 0.702128 (-3925 2650);
PAINT GREEN (-3925 2650);
DISPLAY INVISIBLE (-3925 2650);
FORCEPROP 1 LAST HDL_TAP TRUE
J 2
(-4250 2575);
DISPLAY 0.702128 (-4250 2575);
PAINT GREEN (-4250 2575);
DISPLAY INVISIBLE (-4250 2575);
FORCEPROP 2 LAST ROOM RISER1
J 0
(-4425 2750);
DISPLAY 0.829787 (-4425 2750);
PAINT RED (-4425 2750);
DISPLAY INVISIBLE (-4425 2750);
FORCEPROP 1 LAST PATH I116
J 2
(-3923 2700);
DISPLAY 0.872340 (-3923 2700);
PAINT GREEN (-3923 2700);
DISPLAY INVISIBLE (-3923 2700);
FORCEPROP 2 LAST CDS_LIB standard
J 0
(-3925 2700);
DISPLAY INVISIBLE (-3925 2700);
FORCEADD TAP..6
R 2
(-3775 2550);
FORCEPROP 3 LASTPIN (-3825 2550) SIG_NAME P5E_CPU0_P1_TX_C_DN<7>
J 0
(-3815 2560);
DISPLAY 0.659574 (-3815 2560);
PAINT MONO (-3815 2560);
DISPLAY INVISIBLE (-3815 2560);
FORCEPROP 1 LASTPIN (-3825 2550) BN 7
J 2
(-3773 2558);
DISPLAY 0.680851 (-3773 2558);
PAINT MONO (-3773 2558);
FORCEPROP 2 LAST BOM_COST IO_SLOT
J 0
(-4275 2650);
DISPLAY 0.829787 (-4275 2650);
DISPLAY INVISIBLE (-4275 2650);
FORCEPROP 1 LAST BODY_TYPE PLUMBING
J 2
(-3775 2500);
DISPLAY 0.702128 (-3775 2500);
PAINT GREEN (-3775 2500);
DISPLAY INVISIBLE (-3775 2500);
FORCEPROP 1 LAST HDL_TAP TRUE
J 2
(-4100 2425);
DISPLAY 0.702128 (-4100 2425);
PAINT GREEN (-4100 2425);
DISPLAY INVISIBLE (-4100 2425);
FORCEPROP 2 LAST ROOM RISER1
J 0
(-4275 2600);
DISPLAY 0.829787 (-4275 2600);
PAINT RED (-4275 2600);
DISPLAY INVISIBLE (-4275 2600);
FORCEPROP 1 LAST PATH I117
J 2
(-3773 2550);
DISPLAY 0.872340 (-3773 2550);
PAINT GREEN (-3773 2550);
DISPLAY INVISIBLE (-3773 2550);
FORCEPROP 2 LAST CDS_LIB standard
J 0
(-3775 2550);
DISPLAY INVISIBLE (-3775 2550);
FORCEADD TAP..6
R 2
(-3775 2450);
FORCEPROP 3 LASTPIN (-3825 2450) SIG_NAME P5E_CPU0_P1_TX_C_DN<8>
J 0
(-3815 2460);
DISPLAY 0.659574 (-3815 2460);
PAINT MONO (-3815 2460);
DISPLAY INVISIBLE (-3815 2460);
FORCEPROP 1 LASTPIN (-3825 2450) BN 8
J 2
(-3773 2458);
DISPLAY 0.680851 (-3773 2458);
PAINT MONO (-3773 2458);
FORCEPROP 2 LAST BOM_COST IO_SLOT
J 0
(-4275 2550);
DISPLAY 0.829787 (-4275 2550);
DISPLAY INVISIBLE (-4275 2550);
FORCEPROP 1 LAST BODY_TYPE PLUMBING
J 2
(-3775 2400);
DISPLAY 0.702128 (-3775 2400);
PAINT GREEN (-3775 2400);
DISPLAY INVISIBLE (-3775 2400);
FORCEPROP 1 LAST HDL_TAP TRUE
J 2
(-4100 2325);
DISPLAY 0.702128 (-4100 2325);
PAINT GREEN (-4100 2325);
DISPLAY INVISIBLE (-4100 2325);
FORCEPROP 2 LAST ROOM RISER1
J 0
(-4275 2500);
DISPLAY 0.829787 (-4275 2500);
PAINT RED (-4275 2500);
DISPLAY INVISIBLE (-4275 2500);
FORCEPROP 1 LAST PATH I118
J 2
(-3773 2450);
DISPLAY 0.872340 (-3773 2450);
PAINT GREEN (-3773 2450);
DISPLAY INVISIBLE (-3773 2450);
FORCEPROP 2 LAST CDS_LIB standard
J 0
(-3775 2450);
DISPLAY INVISIBLE (-3775 2450);
FORCEADD TAP..6
R 2
(-3775 2350);
FORCEPROP 3 LASTPIN (-3825 2350) SIG_NAME P5E_CPU0_P1_TX_C_DN<9>
J 0
(-3815 2360);
DISPLAY 0.659574 (-3815 2360);
PAINT MONO (-3815 2360);
DISPLAY INVISIBLE (-3815 2360);
FORCEPROP 1 LASTPIN (-3825 2350) BN 9
J 2
(-3773 2358);
DISPLAY 0.680851 (-3773 2358);
PAINT MONO (-3773 2358);
FORCEPROP 2 LAST BOM_COST IO_SLOT
J 0
(-4275 2450);
DISPLAY 0.829787 (-4275 2450);
DISPLAY INVISIBLE (-4275 2450);
FORCEPROP 1 LAST BODY_TYPE PLUMBING
J 2
(-3775 2300);
DISPLAY 0.702128 (-3775 2300);
PAINT GREEN (-3775 2300);
DISPLAY INVISIBLE (-3775 2300);
FORCEPROP 1 LAST HDL_TAP TRUE
J 2
(-4100 2225);
DISPLAY 0.702128 (-4100 2225);
PAINT GREEN (-4100 2225);
DISPLAY INVISIBLE (-4100 2225);
FORCEPROP 2 LAST ROOM RISER1
J 0
(-4275 2400);
DISPLAY 0.829787 (-4275 2400);
PAINT RED (-4275 2400);
DISPLAY INVISIBLE (-4275 2400);
FORCEPROP 1 LAST PATH I119
J 2
(-3773 2350);
DISPLAY 0.872340 (-3773 2350);
PAINT GREEN (-3773 2350);
DISPLAY INVISIBLE (-3773 2350);
FORCEPROP 2 LAST CDS_LIB standard
J 0
(-3775 2350);
DISPLAY INVISIBLE (-3775 2350);
FORCEADD TAP..6
(-5800 4850);
FORCEPROP 3 LASTPIN (-5750 4850) SIG_NAME P5E_CPU0_P0_TX_DN<9>
J 0
(-5740 4860);
DISPLAY 0.659574 (-5740 4860);
PAINT MONO (-5740 4860);
DISPLAY INVISIBLE (-5740 4860);
FORCEPROP 1 LASTPIN (-5750 4850) BN 9
J 0
(-5802 4858);
DISPLAY 0.680851 (-5802 4858);
PAINT MONO (-5802 4858);
FORCEPROP 2 LAST CDS_LIB standard
J 0
(-5800 4850);
DISPLAY INVISIBLE (-5800 4850);
FORCEPROP 1 LAST PATH I12
J 0
(-5802 4850);
DISPLAY 0.872340 (-5802 4850);
PAINT GREEN (-5802 4850);
DISPLAY INVISIBLE (-5802 4850);
FORCEPROP 1 LAST BODY_TYPE PLUMBING
J 0
(-5800 4800);
DISPLAY 0.574468 (-5800 4800);
PAINT GREEN (-5800 4800);
DISPLAY INVISIBLE (-5800 4800);
FORCEPROP 1 LAST HDL_TAP TRUE
J 0
(-5475 4725);
DISPLAY 0.574468 (-5475 4725);
PAINT GREEN (-5475 4725);
DISPLAY INVISIBLE (-5475 4725);
FORCEADD TAP..6
R 2
(-3775 2250);
FORCEPROP 3 LASTPIN (-3825 2250) SIG_NAME P5E_CPU0_P1_TX_C_DN<10>
J 0
(-3815 2260);
DISPLAY 0.659574 (-3815 2260);
PAINT MONO (-3815 2260);
DISPLAY INVISIBLE (-3815 2260);
FORCEPROP 1 LASTPIN (-3825 2250) BN 10
J 2
(-3773 2258);
DISPLAY 0.680851 (-3773 2258);
PAINT MONO (-3773 2258);
FORCEPROP 2 LAST BOM_COST IO_SLOT
J 0
(-4275 2350);
DISPLAY 0.829787 (-4275 2350);
DISPLAY INVISIBLE (-4275 2350);
FORCEPROP 1 LAST BODY_TYPE PLUMBING
J 2
(-3775 2200);
DISPLAY 0.702128 (-3775 2200);
PAINT GREEN (-3775 2200);
DISPLAY INVISIBLE (-3775 2200);
FORCEPROP 1 LAST HDL_TAP TRUE
J 2
(-4100 2125);
DISPLAY 0.702128 (-4100 2125);
PAINT GREEN (-4100 2125);
DISPLAY INVISIBLE (-4100 2125);
FORCEPROP 2 LAST ROOM RISER1
J 0
(-4275 2300);
DISPLAY 0.829787 (-4275 2300);
PAINT RED (-4275 2300);
DISPLAY INVISIBLE (-4275 2300);
FORCEPROP 1 LAST PATH I120
J 2
(-3773 2250);
DISPLAY 0.872340 (-3773 2250);
PAINT GREEN (-3773 2250);
DISPLAY INVISIBLE (-3773 2250);
FORCEPROP 2 LAST CDS_LIB standard
J 0
(-3775 2250);
DISPLAY INVISIBLE (-3775 2250);
FORCEADD TAP..6
R 2
(-3775 2150);
FORCEPROP 3 LASTPIN (-3825 2150) SIG_NAME P5E_CPU0_P1_TX_C_DN<11>
J 0
(-3815 2160);
DISPLAY 0.659574 (-3815 2160);
PAINT MONO (-3815 2160);
DISPLAY INVISIBLE (-3815 2160);
FORCEPROP 1 LASTPIN (-3825 2150) BN 11
J 2
(-3773 2158);
DISPLAY 0.680851 (-3773 2158);
PAINT MONO (-3773 2158);
FORCEPROP 2 LAST BOM_COST IO_SLOT
J 0
(-4275 2250);
DISPLAY 0.829787 (-4275 2250);
DISPLAY INVISIBLE (-4275 2250);
FORCEPROP 1 LAST BODY_TYPE PLUMBING
J 2
(-3775 2100);
DISPLAY 0.702128 (-3775 2100);
PAINT GREEN (-3775 2100);
DISPLAY INVISIBLE (-3775 2100);
FORCEPROP 1 LAST HDL_TAP TRUE
J 2
(-4100 2025);
DISPLAY 0.702128 (-4100 2025);
PAINT GREEN (-4100 2025);
DISPLAY INVISIBLE (-4100 2025);
FORCEPROP 2 LAST ROOM RISER1
J 0
(-4275 2200);
DISPLAY 0.829787 (-4275 2200);
PAINT RED (-4275 2200);
DISPLAY INVISIBLE (-4275 2200);
FORCEPROP 1 LAST PATH I121
J 2
(-3773 2150);
DISPLAY 0.872340 (-3773 2150);
PAINT GREEN (-3773 2150);
DISPLAY INVISIBLE (-3773 2150);
FORCEPROP 2 LAST CDS_LIB standard
J 0
(-3775 2150);
DISPLAY INVISIBLE (-3775 2150);
FORCEADD TAP..6
R 2
(-3925 2400);
FORCEPROP 3 LASTPIN (-3975 2400) SIG_NAME P5E_CPU0_P1_TX_C_DP<9>
J 0
(-3965 2410);
DISPLAY 0.659574 (-3965 2410);
PAINT MONO (-3965 2410);
DISPLAY INVISIBLE (-3965 2410);
FORCEPROP 1 LASTPIN (-3975 2400) BN 9
J 2
(-3923 2408);
DISPLAY 0.680851 (-3923 2408);
PAINT MONO (-3923 2408);
FORCEPROP 2 LAST BOM_COST IO_SLOT
J 0
(-4425 2500);
DISPLAY 0.829787 (-4425 2500);
DISPLAY INVISIBLE (-4425 2500);
FORCEPROP 1 LAST BODY_TYPE PLUMBING
J 2
(-3925 2350);
DISPLAY 0.702128 (-3925 2350);
PAINT GREEN (-3925 2350);
DISPLAY INVISIBLE (-3925 2350);
FORCEPROP 1 LAST HDL_TAP TRUE
J 2
(-4250 2275);
DISPLAY 0.702128 (-4250 2275);
PAINT GREEN (-4250 2275);
DISPLAY INVISIBLE (-4250 2275);
FORCEPROP 2 LAST ROOM RISER1
J 0
(-4425 2450);
DISPLAY 0.829787 (-4425 2450);
PAINT RED (-4425 2450);
DISPLAY INVISIBLE (-4425 2450);
FORCEPROP 1 LAST PATH I122
J 2
(-3923 2400);
DISPLAY 0.872340 (-3923 2400);
PAINT GREEN (-3923 2400);
DISPLAY INVISIBLE (-3923 2400);
FORCEPROP 2 LAST CDS_LIB standard
J 0
(-3925 2400);
DISPLAY INVISIBLE (-3925 2400);
FORCEADD TAP..6
R 2
(-3925 2500);
FORCEPROP 3 LASTPIN (-3975 2500) SIG_NAME P5E_CPU0_P1_TX_C_DP<8>
J 0
(-3965 2510);
DISPLAY 0.659574 (-3965 2510);
PAINT MONO (-3965 2510);
DISPLAY INVISIBLE (-3965 2510);
FORCEPROP 1 LASTPIN (-3975 2500) BN 8
J 2
(-3923 2508);
DISPLAY 0.680851 (-3923 2508);
PAINT MONO (-3923 2508);
FORCEPROP 2 LAST BOM_COST IO_SLOT
J 0
(-4425 2600);
DISPLAY 0.829787 (-4425 2600);
DISPLAY INVISIBLE (-4425 2600);
FORCEPROP 1 LAST BODY_TYPE PLUMBING
J 2
(-3925 2450);
DISPLAY 0.702128 (-3925 2450);
PAINT GREEN (-3925 2450);
DISPLAY INVISIBLE (-3925 2450);
FORCEPROP 1 LAST HDL_TAP TRUE
J 2
(-4250 2375);
DISPLAY 0.702128 (-4250 2375);
PAINT GREEN (-4250 2375);
DISPLAY INVISIBLE (-4250 2375);
FORCEPROP 2 LAST ROOM RISER1
J 0
(-4425 2550);
DISPLAY 0.829787 (-4425 2550);
PAINT RED (-4425 2550);
DISPLAY INVISIBLE (-4425 2550);
FORCEPROP 1 LAST PATH I123
J 2
(-3923 2500);
DISPLAY 0.872340 (-3923 2500);
PAINT GREEN (-3923 2500);
DISPLAY INVISIBLE (-3923 2500);
FORCEPROP 2 LAST CDS_LIB standard
J 0
(-3925 2500);
DISPLAY INVISIBLE (-3925 2500);
FORCEADD TAP..6
R 2
(-3925 2600);
FORCEPROP 3 LASTPIN (-3975 2600) SIG_NAME P5E_CPU0_P1_TX_C_DP<7>
J 0
(-3965 2610);
DISPLAY 0.659574 (-3965 2610);
PAINT MONO (-3965 2610);
DISPLAY INVISIBLE (-3965 2610);
FORCEPROP 1 LASTPIN (-3975 2600) BN 7
J 2
(-3923 2608);
DISPLAY 0.680851 (-3923 2608);
PAINT MONO (-3923 2608);
FORCEPROP 2 LAST BOM_COST IO_SLOT
J 0
(-4425 2700);
DISPLAY 0.829787 (-4425 2700);
DISPLAY INVISIBLE (-4425 2700);
FORCEPROP 1 LAST BODY_TYPE PLUMBING
J 2
(-3925 2550);
DISPLAY 0.702128 (-3925 2550);
PAINT GREEN (-3925 2550);
DISPLAY INVISIBLE (-3925 2550);
FORCEPROP 1 LAST HDL_TAP TRUE
J 2
(-4250 2475);
DISPLAY 0.702128 (-4250 2475);
PAINT GREEN (-4250 2475);
DISPLAY INVISIBLE (-4250 2475);
FORCEPROP 2 LAST ROOM RISER1
J 0
(-4425 2650);
DISPLAY 0.829787 (-4425 2650);
PAINT RED (-4425 2650);
DISPLAY INVISIBLE (-4425 2650);
FORCEPROP 1 LAST PATH I124
J 2
(-3923 2600);
DISPLAY 0.872340 (-3923 2600);
PAINT GREEN (-3923 2600);
DISPLAY INVISIBLE (-3923 2600);
FORCEPROP 2 LAST CDS_LIB standard
J 0
(-3925 2600);
DISPLAY INVISIBLE (-3925 2600);
FORCEADD TAP..6
R 2
(-3925 2300);
FORCEPROP 3 LASTPIN (-3975 2300) SIG_NAME P5E_CPU0_P1_TX_C_DP<10>
J 0
(-3965 2310);
DISPLAY 0.659574 (-3965 2310);
PAINT MONO (-3965 2310);
DISPLAY INVISIBLE (-3965 2310);
FORCEPROP 1 LASTPIN (-3975 2300) BN 10
J 2
(-3923 2308);
DISPLAY 0.680851 (-3923 2308);
PAINT MONO (-3923 2308);
FORCEPROP 2 LAST BOM_COST IO_SLOT
J 0
(-4425 2400);
DISPLAY 0.829787 (-4425 2400);
DISPLAY INVISIBLE (-4425 2400);
FORCEPROP 1 LAST BODY_TYPE PLUMBING
J 2
(-3925 2250);
DISPLAY 0.702128 (-3925 2250);
PAINT GREEN (-3925 2250);
DISPLAY INVISIBLE (-3925 2250);
FORCEPROP 1 LAST HDL_TAP TRUE
J 2
(-4250 2175);
DISPLAY 0.702128 (-4250 2175);
PAINT GREEN (-4250 2175);
DISPLAY INVISIBLE (-4250 2175);
FORCEPROP 2 LAST ROOM RISER1
J 0
(-4425 2350);
DISPLAY 0.829787 (-4425 2350);
PAINT RED (-4425 2350);
DISPLAY INVISIBLE (-4425 2350);
FORCEPROP 1 LAST PATH I125
J 2
(-3923 2300);
DISPLAY 0.872340 (-3923 2300);
PAINT GREEN (-3923 2300);
DISPLAY INVISIBLE (-3923 2300);
FORCEPROP 2 LAST CDS_LIB standard
J 0
(-3925 2300);
DISPLAY INVISIBLE (-3925 2300);
FORCEADD TAP..6
R 2
(-3925 2200);
FORCEPROP 3 LASTPIN (-3975 2200) SIG_NAME P5E_CPU0_P1_TX_C_DP<11>
J 0
(-3965 2210);
DISPLAY 0.659574 (-3965 2210);
PAINT MONO (-3965 2210);
DISPLAY INVISIBLE (-3965 2210);
FORCEPROP 1 LASTPIN (-3975 2200) BN 11
J 2
(-3923 2208);
DISPLAY 0.680851 (-3923 2208);
PAINT MONO (-3923 2208);
FORCEPROP 2 LAST BOM_COST IO_SLOT
J 0
(-4425 2300);
DISPLAY 0.829787 (-4425 2300);
DISPLAY INVISIBLE (-4425 2300);
FORCEPROP 1 LAST BODY_TYPE PLUMBING
J 2
(-3925 2150);
DISPLAY 0.702128 (-3925 2150);
PAINT GREEN (-3925 2150);
DISPLAY INVISIBLE (-3925 2150);
FORCEPROP 1 LAST HDL_TAP TRUE
J 2
(-4250 2075);
DISPLAY 0.702128 (-4250 2075);
PAINT GREEN (-4250 2075);
DISPLAY INVISIBLE (-4250 2075);
FORCEPROP 2 LAST ROOM RISER1
J 0
(-4425 2250);
DISPLAY 0.829787 (-4425 2250);
PAINT RED (-4425 2250);
DISPLAY INVISIBLE (-4425 2250);
FORCEPROP 1 LAST PATH I126
J 2
(-3923 2200);
DISPLAY 0.872340 (-3923 2200);
PAINT GREEN (-3923 2200);
DISPLAY INVISIBLE (-3923 2200);
FORCEPROP 2 LAST CDS_LIB standard
J 0
(-3925 2200);
DISPLAY INVISIBLE (-3925 2200);
FORCEADD TAP..6
R 2
(-3775 2050);
FORCEPROP 3 LASTPIN (-3825 2050) SIG_NAME P5E_CPU0_P1_TX_C_DN<12>
J 0
(-3815 2060);
DISPLAY 0.659574 (-3815 2060);
PAINT MONO (-3815 2060);
DISPLAY INVISIBLE (-3815 2060);
FORCEPROP 1 LASTPIN (-3825 2050) BN 12
J 2
(-3773 2058);
DISPLAY 0.680851 (-3773 2058);
PAINT MONO (-3773 2058);
FORCEPROP 2 LAST BOM_COST IO_SLOT
J 0
(-4275 2150);
DISPLAY 0.829787 (-4275 2150);
DISPLAY INVISIBLE (-4275 2150);
FORCEPROP 1 LAST BODY_TYPE PLUMBING
J 2
(-3775 2000);
DISPLAY 0.702128 (-3775 2000);
PAINT GREEN (-3775 2000);
DISPLAY INVISIBLE (-3775 2000);
FORCEPROP 1 LAST HDL_TAP TRUE
J 2
(-4100 1925);
DISPLAY 0.702128 (-4100 1925);
PAINT GREEN (-4100 1925);
DISPLAY INVISIBLE (-4100 1925);
FORCEPROP 2 LAST ROOM RISER1
J 0
(-4275 2100);
DISPLAY 0.829787 (-4275 2100);
PAINT RED (-4275 2100);
DISPLAY INVISIBLE (-4275 2100);
FORCEPROP 1 LAST PATH I127
J 2
(-3773 2050);
DISPLAY 0.872340 (-3773 2050);
PAINT GREEN (-3773 2050);
DISPLAY INVISIBLE (-3773 2050);
FORCEPROP 2 LAST CDS_LIB standard
J 0
(-3775 2050);
DISPLAY INVISIBLE (-3775 2050);
FORCEADD TAP..6
R 2
(-3775 1950);
FORCEPROP 3 LASTPIN (-3825 1950) SIG_NAME P5E_CPU0_P1_TX_C_DN<13>
J 0
(-3815 1960);
DISPLAY 0.659574 (-3815 1960);
PAINT MONO (-3815 1960);
DISPLAY INVISIBLE (-3815 1960);
FORCEPROP 1 LASTPIN (-3825 1950) BN 13
J 2
(-3773 1958);
DISPLAY 0.680851 (-3773 1958);
PAINT MONO (-3773 1958);
FORCEPROP 2 LAST BOM_COST IO_SLOT
J 0
(-4275 2050);
DISPLAY 0.829787 (-4275 2050);
DISPLAY INVISIBLE (-4275 2050);
FORCEPROP 1 LAST BODY_TYPE PLUMBING
J 2
(-3775 1900);
DISPLAY 0.702128 (-3775 1900);
PAINT GREEN (-3775 1900);
DISPLAY INVISIBLE (-3775 1900);
FORCEPROP 1 LAST HDL_TAP TRUE
J 2
(-4100 1825);
DISPLAY 0.702128 (-4100 1825);
PAINT GREEN (-4100 1825);
DISPLAY INVISIBLE (-4100 1825);
FORCEPROP 2 LAST ROOM RISER1
J 0
(-4275 2000);
DISPLAY 0.829787 (-4275 2000);
PAINT RED (-4275 2000);
DISPLAY INVISIBLE (-4275 2000);
FORCEPROP 1 LAST PATH I128
J 2
(-3773 1950);
DISPLAY 0.872340 (-3773 1950);
PAINT GREEN (-3773 1950);
DISPLAY INVISIBLE (-3773 1950);
FORCEPROP 2 LAST CDS_LIB standard
J 0
(-3775 1950);
DISPLAY INVISIBLE (-3775 1950);
FORCEADD TAP..6
R 2
(-3775 1850);
FORCEPROP 3 LASTPIN (-3825 1850) SIG_NAME P5E_CPU0_P1_TX_C_DN<14>
J 0
(-3815 1860);
DISPLAY 0.659574 (-3815 1860);
PAINT MONO (-3815 1860);
DISPLAY INVISIBLE (-3815 1860);
FORCEPROP 1 LASTPIN (-3825 1850) BN 14
J 2
(-3773 1858);
DISPLAY 0.680851 (-3773 1858);
PAINT MONO (-3773 1858);
FORCEPROP 2 LAST BOM_COST IO_SLOT
J 0
(-4275 1950);
DISPLAY 0.829787 (-4275 1950);
DISPLAY INVISIBLE (-4275 1950);
FORCEPROP 1 LAST BODY_TYPE PLUMBING
J 2
(-3775 1800);
DISPLAY 0.702128 (-3775 1800);
PAINT GREEN (-3775 1800);
DISPLAY INVISIBLE (-3775 1800);
FORCEPROP 1 LAST HDL_TAP TRUE
J 2
(-4100 1725);
DISPLAY 0.702128 (-4100 1725);
PAINT GREEN (-4100 1725);
DISPLAY INVISIBLE (-4100 1725);
FORCEPROP 2 LAST ROOM RISER1
J 0
(-4275 1900);
DISPLAY 0.829787 (-4275 1900);
PAINT RED (-4275 1900);
DISPLAY INVISIBLE (-4275 1900);
FORCEPROP 1 LAST PATH I129
J 2
(-3773 1850);
DISPLAY 0.872340 (-3773 1850);
PAINT GREEN (-3773 1850);
DISPLAY INVISIBLE (-3773 1850);
FORCEPROP 2 LAST CDS_LIB standard
J 0
(-3775 1850);
DISPLAY INVISIBLE (-3775 1850);
FORCEADD TAP..6
(-5800 4950);
FORCEPROP 3 LASTPIN (-5750 4950) SIG_NAME P5E_CPU0_P0_TX_DN<8>
J 0
(-5740 4960);
DISPLAY 0.659574 (-5740 4960);
PAINT MONO (-5740 4960);
DISPLAY INVISIBLE (-5740 4960);
FORCEPROP 1 LASTPIN (-5750 4950) BN 8
J 0
(-5802 4958);
DISPLAY 0.680851 (-5802 4958);
PAINT MONO (-5802 4958);
FORCEPROP 2 LAST CDS_LIB standard
J 0
(-5800 4950);
DISPLAY INVISIBLE (-5800 4950);
FORCEPROP 1 LAST PATH I13
J 0
(-5802 4950);
DISPLAY 0.872340 (-5802 4950);
PAINT GREEN (-5802 4950);
DISPLAY INVISIBLE (-5802 4950);
FORCEPROP 1 LAST BODY_TYPE PLUMBING
J 0
(-5800 4900);
DISPLAY 0.574468 (-5800 4900);
PAINT GREEN (-5800 4900);
DISPLAY INVISIBLE (-5800 4900);
FORCEPROP 1 LAST HDL_TAP TRUE
J 0
(-5475 4825);
DISPLAY 0.574468 (-5475 4825);
PAINT GREEN (-5475 4825);
DISPLAY INVISIBLE (-5475 4825);
FORCEADD TAP..6
R 2
(-3775 1750);
FORCEPROP 3 LASTPIN (-3825 1750) SIG_NAME P5E_CPU0_P1_TX_C_DN<15>
J 0
(-3815 1760);
DISPLAY 0.659574 (-3815 1760);
PAINT MONO (-3815 1760);
DISPLAY INVISIBLE (-3815 1760);
FORCEPROP 1 LASTPIN (-3825 1750) BN 15
J 2
(-3773 1758);
DISPLAY 0.680851 (-3773 1758);
PAINT MONO (-3773 1758);
FORCEPROP 2 LAST BOM_COST IO_SLOT
J 0
(-4275 1850);
DISPLAY 0.829787 (-4275 1850);
DISPLAY INVISIBLE (-4275 1850);
FORCEPROP 1 LAST BODY_TYPE PLUMBING
J 2
(-3775 1700);
DISPLAY 0.702128 (-3775 1700);
PAINT GREEN (-3775 1700);
DISPLAY INVISIBLE (-3775 1700);
FORCEPROP 1 LAST HDL_TAP TRUE
J 2
(-4100 1625);
DISPLAY 0.702128 (-4100 1625);
PAINT GREEN (-4100 1625);
DISPLAY INVISIBLE (-4100 1625);
FORCEPROP 2 LAST ROOM RISER1
J 0
(-4275 1800);
DISPLAY 0.829787 (-4275 1800);
PAINT RED (-4275 1800);
DISPLAY INVISIBLE (-4275 1800);
FORCEPROP 1 LAST PATH I130
J 2
(-3773 1750);
DISPLAY 0.872340 (-3773 1750);
PAINT GREEN (-3773 1750);
DISPLAY INVISIBLE (-3773 1750);
FORCEPROP 2 LAST CDS_LIB standard
J 0
(-3775 1750);
DISPLAY INVISIBLE (-3775 1750);
FORCEADD TAP..6
R 2
(-3925 1900);
FORCEPROP 3 LASTPIN (-3975 1900) SIG_NAME P5E_CPU0_P1_TX_C_DP<14>
J 0
(-3965 1910);
DISPLAY 0.659574 (-3965 1910);
PAINT MONO (-3965 1910);
DISPLAY INVISIBLE (-3965 1910);
FORCEPROP 1 LASTPIN (-3975 1900) BN 14
J 2
(-3923 1908);
DISPLAY 0.680851 (-3923 1908);
PAINT MONO (-3923 1908);
FORCEPROP 2 LAST BOM_COST IO_SLOT
J 0
(-4425 2000);
DISPLAY 0.829787 (-4425 2000);
DISPLAY INVISIBLE (-4425 2000);
FORCEPROP 1 LAST BODY_TYPE PLUMBING
J 2
(-3925 1850);
DISPLAY 0.702128 (-3925 1850);
PAINT GREEN (-3925 1850);
DISPLAY INVISIBLE (-3925 1850);
FORCEPROP 1 LAST HDL_TAP TRUE
J 2
(-4250 1775);
DISPLAY 0.702128 (-4250 1775);
PAINT GREEN (-4250 1775);
DISPLAY INVISIBLE (-4250 1775);
FORCEPROP 2 LAST ROOM RISER1
J 0
(-4425 1950);
DISPLAY 0.829787 (-4425 1950);
PAINT RED (-4425 1950);
DISPLAY INVISIBLE (-4425 1950);
FORCEPROP 1 LAST PATH I131
J 2
(-3923 1900);
DISPLAY 0.872340 (-3923 1900);
PAINT GREEN (-3923 1900);
DISPLAY INVISIBLE (-3923 1900);
FORCEPROP 2 LAST CDS_LIB standard
J 0
(-3925 1900);
DISPLAY INVISIBLE (-3925 1900);
FORCEADD TAP..6
R 2
(-3925 2000);
FORCEPROP 3 LASTPIN (-3975 2000) SIG_NAME P5E_CPU0_P1_TX_C_DP<13>
J 0
(-3965 2010);
DISPLAY 0.659574 (-3965 2010);
PAINT MONO (-3965 2010);
DISPLAY INVISIBLE (-3965 2010);
FORCEPROP 1 LASTPIN (-3975 2000) BN 13
J 2
(-3923 2008);
DISPLAY 0.680851 (-3923 2008);
PAINT MONO (-3923 2008);
FORCEPROP 2 LAST BOM_COST IO_SLOT
J 0
(-4425 2100);
DISPLAY 0.829787 (-4425 2100);
DISPLAY INVISIBLE (-4425 2100);
FORCEPROP 1 LAST BODY_TYPE PLUMBING
J 2
(-3925 1950);
DISPLAY 0.702128 (-3925 1950);
PAINT GREEN (-3925 1950);
DISPLAY INVISIBLE (-3925 1950);
FORCEPROP 1 LAST HDL_TAP TRUE
J 2
(-4250 1875);
DISPLAY 0.702128 (-4250 1875);
PAINT GREEN (-4250 1875);
DISPLAY INVISIBLE (-4250 1875);
FORCEPROP 2 LAST ROOM RISER1
J 0
(-4425 2050);
DISPLAY 0.829787 (-4425 2050);
PAINT RED (-4425 2050);
DISPLAY INVISIBLE (-4425 2050);
FORCEPROP 1 LAST PATH I132
J 2
(-3923 2000);
DISPLAY 0.872340 (-3923 2000);
PAINT GREEN (-3923 2000);
DISPLAY INVISIBLE (-3923 2000);
FORCEPROP 2 LAST CDS_LIB standard
J 0
(-3925 2000);
DISPLAY INVISIBLE (-3925 2000);
FORCEADD TAP..6
R 2
(-3925 2100);
FORCEPROP 3 LASTPIN (-3975 2100) SIG_NAME P5E_CPU0_P1_TX_C_DP<12>
J 0
(-3965 2110);
DISPLAY 0.659574 (-3965 2110);
PAINT MONO (-3965 2110);
DISPLAY INVISIBLE (-3965 2110);
FORCEPROP 1 LASTPIN (-3975 2100) BN 12
J 2
(-3923 2108);
DISPLAY 0.680851 (-3923 2108);
PAINT MONO (-3923 2108);
FORCEPROP 2 LAST BOM_COST IO_SLOT
J 0
(-4425 2200);
DISPLAY 0.829787 (-4425 2200);
DISPLAY INVISIBLE (-4425 2200);
FORCEPROP 1 LAST BODY_TYPE PLUMBING
J 2
(-3925 2050);
DISPLAY 0.702128 (-3925 2050);
PAINT GREEN (-3925 2050);
DISPLAY INVISIBLE (-3925 2050);
FORCEPROP 1 LAST HDL_TAP TRUE
J 2
(-4250 1975);
DISPLAY 0.702128 (-4250 1975);
PAINT GREEN (-4250 1975);
DISPLAY INVISIBLE (-4250 1975);
FORCEPROP 2 LAST ROOM RISER1
J 0
(-4425 2150);
DISPLAY 0.829787 (-4425 2150);
PAINT RED (-4425 2150);
DISPLAY INVISIBLE (-4425 2150);
FORCEPROP 1 LAST PATH I133
J 2
(-3923 2100);
DISPLAY 0.872340 (-3923 2100);
PAINT GREEN (-3923 2100);
DISPLAY INVISIBLE (-3923 2100);
FORCEPROP 2 LAST CDS_LIB standard
J 0
(-3925 2100);
DISPLAY INVISIBLE (-3925 2100);
FORCEADD TAP..6
R 2
(-3925 1800);
FORCEPROP 3 LASTPIN (-3975 1800) SIG_NAME P5E_CPU0_P1_TX_C_DP<15>
J 0
(-3965 1810);
DISPLAY 0.659574 (-3965 1810);
PAINT MONO (-3965 1810);
DISPLAY INVISIBLE (-3965 1810);
FORCEPROP 1 LASTPIN (-3975 1800) BN 15
J 2
(-3923 1808);
DISPLAY 0.680851 (-3923 1808);
PAINT MONO (-3923 1808);
FORCEPROP 2 LAST BOM_COST IO_SLOT
J 0
(-4425 1900);
DISPLAY 0.829787 (-4425 1900);
DISPLAY INVISIBLE (-4425 1900);
FORCEPROP 1 LAST BODY_TYPE PLUMBING
J 2
(-3925 1750);
DISPLAY 0.702128 (-3925 1750);
PAINT GREEN (-3925 1750);
DISPLAY INVISIBLE (-3925 1750);
FORCEPROP 1 LAST HDL_TAP TRUE
J 2
(-4250 1675);
DISPLAY 0.702128 (-4250 1675);
PAINT GREEN (-4250 1675);
DISPLAY INVISIBLE (-4250 1675);
FORCEPROP 2 LAST ROOM RISER1
J 0
(-4425 1850);
DISPLAY 0.829787 (-4425 1850);
PAINT RED (-4425 1850);
DISPLAY INVISIBLE (-4425 1850);
FORCEPROP 1 LAST PATH I134
J 2
(-3923 1800);
DISPLAY 0.872340 (-3923 1800);
PAINT GREEN (-3923 1800);
DISPLAY INVISIBLE (-3923 1800);
FORCEPROP 2 LAST CDS_LIB standard
J 0
(-3925 1800);
DISPLAY INVISIBLE (-3925 1800);
FORCEADD Q_CAP_DIFFBUS..2
(-4925 3300);
FORCEPROP 1 LAST LOCATION C554
J 0
(-4775 3300);
DISPLAY 0.723404 (-4775 3300);
PAINT GREEN (-4775 3300);
FORCEPROP 0 LAST $SEC 1
J 0
(-5125 3450);
DISPLAY 0.680851 (-5125 3450);
PAINT MONO (-5125 3450);
DISPLAY INVISIBLE (-5125 3450);
FORCEPROP 0 LAST CDS_SEC 1
J 0
(-5125 3450);
DISPLAY 0.680851 (-5125 3450);
DISPLAY INVISIBLE (-5125 3450);
FORCEPROP 0 LASTPIN (-5000 3300) $PN 1
J 2
(-5010 3310);
DISPLAY 0.680851 (-5010 3310);
PAINT MONO (-5010 3310);
FORCEPROP 0 LASTPIN (-4850 3300) $PN 2
J 0
(-4840 3310);
DISPLAY 0.680851 (-4840 3310);
PAINT MONO (-4840 3310);
FORCEPROP 2 LAST PACK_TYPE C0201
J 0
(-5150 3350);
DISPLAY 0.680851 (-5150 3350);
FORCEPROP 1 LAST MATERIAL X6S
J 0
(-4975 3350);
DISPLAY 0.723404 (-4975 3350);
PAINT GREEN (-4975 3350);
FORCEPROP 2 LAST TOLERANCE 20%
J 0
(-4850 3350);
DISPLAY 0.680851 (-4850 3350);
FORCEPROP 1 LAST PART_NUMBER SP_CH4221MEE01
J 0
(-5125 3400);
DISPLAY 0.723404 (-5125 3400);
PAINT GREEN (-5125 3400);
FORCEPROP 2 LAST VOLTAGE 6.3V
J 0
(-4725 3350);
DISPLAY 0.680851 (-4725 3350);
FORCEPROP 2 LAST VALUE DIFF BUS_0.22UF
J 0
(-5500 3300);
DISPLAY 0.680851 (-5500 3300);
FORCEPROP 1 LAST PIN_NAMES_ROTATE True
J 0
(-4925 3300);
DISPLAY 0.489362 (-4925 3300);
PAINT GREEN (-4925 3300);
DISPLAY INVISIBLE (-4925 3300);
FORCEPROP 1 LAST CDS_LMAN_SYM_OUTLINE -25,50,25,-50
J 0
(-4925 3300);
DISPLAY 0.468085 (-4925 3300);
PAINT GREEN (-4925 3300);
DISPLAY INVISIBLE (-4925 3300);
FORCEPROP 1 LAST PATH I135
J 0
(-4925 3300);
DISPLAY 0.723404 (-4925 3300);
DISPLAY INVISIBLE (-4925 3300);
FORCEPROP 2 LAST CDS_LIB pure_quanta
J 0
(-4925 3300);
DISPLAY INVISIBLE (-4925 3300);
FORCEADD Q_CAP_DIFFBUS..2
R 2
(-4925 3250);
FORCEPROP 1 LAST LOCATION C555
J 2
(-4675 3250);
DISPLAY 0.723404 (-4675 3250);
PAINT GREEN (-4675 3250);
FORCEPROP 0 LAST $SEC 1
J 0
(-4675 3300);
DISPLAY 0.680851 (-4675 3300);
PAINT MONO (-4675 3300);
DISPLAY INVISIBLE (-4675 3300);
FORCEPROP 0 LAST CDS_SEC 1
J 0
(-4675 3300);
DISPLAY 0.680851 (-4675 3300);
DISPLAY INVISIBLE (-4675 3300);
FORCEPROP 0 LASTPIN (-4850 3250) $PN 1
J 0
(-4840 3260);
DISPLAY 0.680851 (-4840 3260);
PAINT MONO (-4840 3260);
FORCEPROP 0 LASTPIN (-5000 3250) $PN 2
J 2
(-5010 3260);
DISPLAY 0.680851 (-5010 3260);
PAINT MONO (-5010 3260);
FORCEPROP 2 LAST VALUE DIFF BUS_0.22UF
J 2
(-5050 3250);
DISPLAY 0.553191 (-5050 3250);
FORCEPROP 0 LAST VOLTAGE 6.3V
J 2
(-5000 3425);
DISPLAY 0.680851 (-5000 3425);
DISPLAY INVISIBLE (-5000 3425);
FORCEPROP 0 LAST TOLERANCE 20%
J 2
(-5000 3375);
DISPLAY 0.680851 (-5000 3375);
DISPLAY INVISIBLE (-5000 3375);
FORCEPROP 1 LAST PART_NUMBER SP_CH4221MEE01
J 2
(-4900 3325);
DISPLAY 0.723404 (-4900 3325);
PAINT GREEN (-4900 3325);
DISPLAY INVISIBLE (-4900 3325);
FORCEPROP 1 LAST MATERIAL X6S
J 2
(-4775 3300);
DISPLAY 0.723404 (-4775 3300);
PAINT GREEN (-4775 3300);
DISPLAY INVISIBLE (-4775 3300);
FORCEPROP 1 LAST PIN_NAMES_ROTATE True
J 2
(-4925 3250);
DISPLAY 0.489362 (-4925 3250);
PAINT GREEN (-4925 3250);
DISPLAY INVISIBLE (-4925 3250);
FORCEPROP 0 LAST PACK_TYPE C0201
J 2
(-5075 3250);
DISPLAY 0.680851 (-5075 3250);
DISPLAY INVISIBLE (-5075 3250);
FORCEPROP 1 LAST CDS_LMAN_SYM_OUTLINE -25,50,25,-50
J 2
(-4925 3250);
DISPLAY 0.468085 (-4925 3250);
PAINT GREEN (-4925 3250);
DISPLAY INVISIBLE (-4925 3250);
FORCEPROP 1 LAST PATH I136
J 2
(-4925 3250);
DISPLAY 0.723404 (-4925 3250);
DISPLAY INVISIBLE (-4925 3250);
FORCEPROP 2 LAST CDS_LIB pure_quanta
J 0
(-4925 3250);
DISPLAY INVISIBLE (-4925 3250);
FORCEADD Q_CAP_DIFFBUS..2
R 2
(-4925 3200);
FORCEPROP 1 LAST LOCATION C556
J 2
(-4675 3200);
DISPLAY 0.723404 (-4675 3200);
PAINT GREEN (-4675 3200);
FORCEPROP 0 LAST $SEC 1
J 0
(-4675 3250);
DISPLAY 0.680851 (-4675 3250);
PAINT MONO (-4675 3250);
DISPLAY INVISIBLE (-4675 3250);
FORCEPROP 0 LAST CDS_SEC 1
J 0
(-4675 3250);
DISPLAY 0.680851 (-4675 3250);
DISPLAY INVISIBLE (-4675 3250);
FORCEPROP 0 LASTPIN (-4850 3200) $PN 1
J 0
(-4840 3210);
DISPLAY 0.680851 (-4840 3210);
PAINT MONO (-4840 3210);
FORCEPROP 0 LASTPIN (-5000 3200) $PN 2
J 2
(-5010 3210);
DISPLAY 0.680851 (-5010 3210);
PAINT MONO (-5010 3210);
FORCEPROP 2 LAST VALUE DIFF BUS_0.22UF
J 2
(-5050 3200);
DISPLAY 0.553191 (-5050 3200);
FORCEPROP 0 LAST VOLTAGE 6.3V
J 2
(-5000 3375);
DISPLAY 0.680851 (-5000 3375);
DISPLAY INVISIBLE (-5000 3375);
FORCEPROP 0 LAST TOLERANCE 20%
J 2
(-5000 3325);
DISPLAY 0.680851 (-5000 3325);
DISPLAY INVISIBLE (-5000 3325);
FORCEPROP 1 LAST PART_NUMBER SP_CH4221MEE01
J 2
(-4900 3275);
DISPLAY 0.723404 (-4900 3275);
PAINT GREEN (-4900 3275);
DISPLAY INVISIBLE (-4900 3275);
FORCEPROP 1 LAST MATERIAL X6S
J 2
(-4775 3250);
DISPLAY 0.723404 (-4775 3250);
PAINT GREEN (-4775 3250);
DISPLAY INVISIBLE (-4775 3250);
FORCEPROP 1 LAST PIN_NAMES_ROTATE True
J 2
(-4925 3200);
DISPLAY 0.489362 (-4925 3200);
PAINT GREEN (-4925 3200);
DISPLAY INVISIBLE (-4925 3200);
FORCEPROP 0 LAST PACK_TYPE C0201
J 2
(-5075 3200);
DISPLAY 0.680851 (-5075 3200);
DISPLAY INVISIBLE (-5075 3200);
FORCEPROP 1 LAST CDS_LMAN_SYM_OUTLINE -25,50,25,-50
J 2
(-4925 3200);
DISPLAY 0.468085 (-4925 3200);
PAINT GREEN (-4925 3200);
DISPLAY INVISIBLE (-4925 3200);
FORCEPROP 1 LAST PATH I137
J 2
(-4925 3200);
DISPLAY 0.723404 (-4925 3200);
DISPLAY INVISIBLE (-4925 3200);
FORCEPROP 2 LAST CDS_LIB pure_quanta
J 0
(-4925 3200);
DISPLAY INVISIBLE (-4925 3200);
FORCEADD Q_CAP_DIFFBUS..2
R 2
(-4925 3150);
FORCEPROP 1 LAST LOCATION C557
J 2
(-4675 3150);
DISPLAY 0.723404 (-4675 3150);
PAINT GREEN (-4675 3150);
FORCEPROP 0 LAST $SEC 1
J 0
(-4675 3200);
DISPLAY 0.680851 (-4675 3200);
PAINT MONO (-4675 3200);
DISPLAY INVISIBLE (-4675 3200);
FORCEPROP 0 LAST CDS_SEC 1
J 0
(-4675 3200);
DISPLAY 0.680851 (-4675 3200);
DISPLAY INVISIBLE (-4675 3200);
FORCEPROP 0 LASTPIN (-4850 3150) $PN 1
J 0
(-4840 3160);
DISPLAY 0.680851 (-4840 3160);
PAINT MONO (-4840 3160);
FORCEPROP 0 LASTPIN (-5000 3150) $PN 2
J 2
(-5010 3160);
DISPLAY 0.680851 (-5010 3160);
PAINT MONO (-5010 3160);
FORCEPROP 2 LAST VALUE DIFF BUS_0.22UF
J 2
(-5050 3150);
DISPLAY 0.553191 (-5050 3150);
FORCEPROP 0 LAST VOLTAGE 6.3V
J 2
(-5000 3325);
DISPLAY 0.680851 (-5000 3325);
DISPLAY INVISIBLE (-5000 3325);
FORCEPROP 0 LAST TOLERANCE 20%
J 2
(-5000 3275);
DISPLAY 0.680851 (-5000 3275);
DISPLAY INVISIBLE (-5000 3275);
FORCEPROP 1 LAST PART_NUMBER SP_CH4221MEE01
J 2
(-4900 3225);
DISPLAY 0.723404 (-4900 3225);
PAINT GREEN (-4900 3225);
DISPLAY INVISIBLE (-4900 3225);
FORCEPROP 1 LAST MATERIAL X6S
J 2
(-4775 3200);
DISPLAY 0.723404 (-4775 3200);
PAINT GREEN (-4775 3200);
DISPLAY INVISIBLE (-4775 3200);
FORCEPROP 1 LAST PIN_NAMES_ROTATE True
J 2
(-4925 3150);
DISPLAY 0.489362 (-4925 3150);
PAINT GREEN (-4925 3150);
DISPLAY INVISIBLE (-4925 3150);
FORCEPROP 0 LAST PACK_TYPE C0201
J 2
(-5075 3150);
DISPLAY 0.680851 (-5075 3150);
DISPLAY INVISIBLE (-5075 3150);
FORCEPROP 1 LAST CDS_LMAN_SYM_OUTLINE -25,50,25,-50
J 2
(-4925 3150);
DISPLAY 0.468085 (-4925 3150);
PAINT GREEN (-4925 3150);
DISPLAY INVISIBLE (-4925 3150);
FORCEPROP 1 LAST PATH I138
J 2
(-4925 3150);
DISPLAY 0.723404 (-4925 3150);
DISPLAY INVISIBLE (-4925 3150);
FORCEPROP 2 LAST CDS_LIB pure_quanta
J 0
(-4925 3150);
DISPLAY INVISIBLE (-4925 3150);
FORCEADD Q_CAP_DIFFBUS..2
R 2
(-4925 3100);
FORCEPROP 1 LAST LOCATION C558
J 2
(-4675 3100);
DISPLAY 0.723404 (-4675 3100);
PAINT GREEN (-4675 3100);
FORCEPROP 0 LAST $SEC 1
J 0
(-4675 3150);
DISPLAY 0.680851 (-4675 3150);
PAINT MONO (-4675 3150);
DISPLAY INVISIBLE (-4675 3150);
FORCEPROP 0 LAST CDS_SEC 1
J 0
(-4675 3150);
DISPLAY 0.680851 (-4675 3150);
DISPLAY INVISIBLE (-4675 3150);
FORCEPROP 0 LASTPIN (-4850 3100) $PN 1
J 0
(-4840 3110);
DISPLAY 0.680851 (-4840 3110);
PAINT MONO (-4840 3110);
FORCEPROP 0 LASTPIN (-5000 3100) $PN 2
J 2
(-5010 3110);
DISPLAY 0.680851 (-5010 3110);
PAINT MONO (-5010 3110);
FORCEPROP 2 LAST VALUE DIFF BUS_0.22UF
J 2
(-5050 3100);
DISPLAY 0.553191 (-5050 3100);
FORCEPROP 0 LAST PACK_TYPE C0201
J 2
(-5075 3100);
DISPLAY 0.680851 (-5075 3100);
DISPLAY INVISIBLE (-5075 3100);
FORCEPROP 1 LAST PIN_NAMES_ROTATE True
J 2
(-4925 3100);
DISPLAY 0.489362 (-4925 3100);
PAINT GREEN (-4925 3100);
DISPLAY INVISIBLE (-4925 3100);
FORCEPROP 1 LAST MATERIAL X6S
J 2
(-4775 3150);
DISPLAY 0.723404 (-4775 3150);
PAINT GREEN (-4775 3150);
DISPLAY INVISIBLE (-4775 3150);
FORCEPROP 1 LAST PART_NUMBER SP_CH4221MEE01
J 2
(-4900 3175);
DISPLAY 0.723404 (-4900 3175);
PAINT GREEN (-4900 3175);
DISPLAY INVISIBLE (-4900 3175);
FORCEPROP 0 LAST TOLERANCE 20%
J 2
(-5000 3225);
DISPLAY 0.680851 (-5000 3225);
DISPLAY INVISIBLE (-5000 3225);
FORCEPROP 0 LAST VOLTAGE 6.3V
J 2
(-5000 3275);
DISPLAY 0.680851 (-5000 3275);
DISPLAY INVISIBLE (-5000 3275);
FORCEPROP 1 LAST CDS_LMAN_SYM_OUTLINE -25,50,25,-50
J 2
(-4925 3100);
DISPLAY 0.468085 (-4925 3100);
PAINT GREEN (-4925 3100);
DISPLAY INVISIBLE (-4925 3100);
FORCEPROP 1 LAST PATH I139
J 2
(-4925 3100);
DISPLAY 0.723404 (-4925 3100);
DISPLAY INVISIBLE (-4925 3100);
FORCEPROP 2 LAST CDS_LIB pure_quanta
J 0
(-4925 3100);
DISPLAY INVISIBLE (-4925 3100);
FORCEADD TAP..6
(-5800 5050);
FORCEPROP 3 LASTPIN (-5750 5050) SIG_NAME P5E_CPU0_P0_TX_DN<7>
J 0
(-5740 5060);
DISPLAY 0.659574 (-5740 5060);
PAINT MONO (-5740 5060);
DISPLAY INVISIBLE (-5740 5060);
FORCEPROP 1 LASTPIN (-5750 5050) BN 7
J 0
(-5802 5058);
DISPLAY 0.680851 (-5802 5058);
PAINT MONO (-5802 5058);
FORCEPROP 2 LAST CDS_LIB standard
J 0
(-5800 5050);
DISPLAY INVISIBLE (-5800 5050);
FORCEPROP 1 LAST PATH I14
J 0
(-5802 5050);
DISPLAY 0.872340 (-5802 5050);
PAINT GREEN (-5802 5050);
DISPLAY INVISIBLE (-5802 5050);
FORCEPROP 1 LAST BODY_TYPE PLUMBING
J 0
(-5800 5000);
DISPLAY 0.574468 (-5800 5000);
PAINT GREEN (-5800 5000);
DISPLAY INVISIBLE (-5800 5000);
FORCEPROP 1 LAST HDL_TAP TRUE
J 0
(-5475 4925);
DISPLAY 0.574468 (-5475 4925);
PAINT GREEN (-5475 4925);
DISPLAY INVISIBLE (-5475 4925);
FORCEADD Q_CAP_DIFFBUS..2
R 2
(-4925 3050);
FORCEPROP 1 LAST LOCATION C559
J 2
(-4675 3050);
DISPLAY 0.723404 (-4675 3050);
PAINT GREEN (-4675 3050);
FORCEPROP 0 LAST $SEC 1
J 0
(-4675 3100);
DISPLAY 0.680851 (-4675 3100);
PAINT MONO (-4675 3100);
DISPLAY INVISIBLE (-4675 3100);
FORCEPROP 0 LAST CDS_SEC 1
J 0
(-4675 3100);
DISPLAY 0.680851 (-4675 3100);
DISPLAY INVISIBLE (-4675 3100);
FORCEPROP 0 LASTPIN (-4850 3050) $PN 1
J 0
(-4840 3060);
DISPLAY 0.680851 (-4840 3060);
PAINT MONO (-4840 3060);
FORCEPROP 0 LASTPIN (-5000 3050) $PN 2
J 2
(-5010 3060);
DISPLAY 0.680851 (-5010 3060);
PAINT MONO (-5010 3060);
FORCEPROP 2 LAST VALUE DIFF BUS_0.22UF
J 2
(-5050 3050);
DISPLAY 0.553191 (-5050 3050);
FORCEPROP 0 LAST VOLTAGE 6.3V
J 2
(-5000 3225);
DISPLAY 0.680851 (-5000 3225);
DISPLAY INVISIBLE (-5000 3225);
FORCEPROP 0 LAST TOLERANCE 20%
J 2
(-5000 3175);
DISPLAY 0.680851 (-5000 3175);
DISPLAY INVISIBLE (-5000 3175);
FORCEPROP 1 LAST PART_NUMBER SP_CH4221MEE01
J 2
(-4900 3125);
DISPLAY 0.723404 (-4900 3125);
PAINT GREEN (-4900 3125);
DISPLAY INVISIBLE (-4900 3125);
FORCEPROP 1 LAST MATERIAL X6S
J 2
(-4775 3100);
DISPLAY 0.723404 (-4775 3100);
PAINT GREEN (-4775 3100);
DISPLAY INVISIBLE (-4775 3100);
FORCEPROP 1 LAST PIN_NAMES_ROTATE True
J 2
(-4925 3050);
DISPLAY 0.489362 (-4925 3050);
PAINT GREEN (-4925 3050);
DISPLAY INVISIBLE (-4925 3050);
FORCEPROP 0 LAST PACK_TYPE C0201
J 2
(-5075 3050);
DISPLAY 0.680851 (-5075 3050);
DISPLAY INVISIBLE (-5075 3050);
FORCEPROP 1 LAST CDS_LMAN_SYM_OUTLINE -25,50,25,-50
J 2
(-4925 3050);
DISPLAY 0.468085 (-4925 3050);
PAINT GREEN (-4925 3050);
DISPLAY INVISIBLE (-4925 3050);
FORCEPROP 1 LAST PATH I140
J 2
(-4925 3050);
DISPLAY 0.723404 (-4925 3050);
DISPLAY INVISIBLE (-4925 3050);
FORCEPROP 2 LAST CDS_LIB pure_quanta
J 0
(-4925 3050);
DISPLAY INVISIBLE (-4925 3050);
FORCEADD Q_CAP_DIFFBUS..2
R 2
(-4925 3000);
FORCEPROP 1 LAST LOCATION C560
J 2
(-4725 3000);
DISPLAY 0.723404 (-4725 3000);
PAINT GREEN (-4725 3000);
FORCEPROP 0 LAST $SEC 1
J 0
(-4725 3050);
DISPLAY 0.680851 (-4725 3050);
PAINT MONO (-4725 3050);
DISPLAY INVISIBLE (-4725 3050);
FORCEPROP 0 LAST CDS_SEC 1
J 0
(-4725 3050);
DISPLAY 0.680851 (-4725 3050);
DISPLAY INVISIBLE (-4725 3050);
FORCEPROP 0 LASTPIN (-4850 3000) $PN 1
J 0
(-4840 3010);
DISPLAY 0.680851 (-4840 3010);
PAINT MONO (-4840 3010);
FORCEPROP 0 LASTPIN (-5000 3000) $PN 2
J 2
(-5010 3010);
DISPLAY 0.680851 (-5010 3010);
PAINT MONO (-5010 3010);
FORCEPROP 2 LAST VALUE DIFF BUS_0.22UF
J 2
(-5050 3000);
DISPLAY 0.553191 (-5050 3000);
FORCEPROP 0 LAST VOLTAGE 6.3V
J 2
(-5000 3175);
DISPLAY 0.680851 (-5000 3175);
DISPLAY INVISIBLE (-5000 3175);
FORCEPROP 0 LAST TOLERANCE 20%
J 2
(-5000 3125);
DISPLAY 0.680851 (-5000 3125);
DISPLAY INVISIBLE (-5000 3125);
FORCEPROP 1 LAST PART_NUMBER SP_CH4221MEE01
J 2
(-4900 3075);
DISPLAY 0.723404 (-4900 3075);
PAINT GREEN (-4900 3075);
DISPLAY INVISIBLE (-4900 3075);
FORCEPROP 1 LAST MATERIAL X6S
J 2
(-4775 3050);
DISPLAY 0.723404 (-4775 3050);
PAINT GREEN (-4775 3050);
DISPLAY INVISIBLE (-4775 3050);
FORCEPROP 1 LAST PIN_NAMES_ROTATE True
J 2
(-4925 3000);
DISPLAY 0.489362 (-4925 3000);
PAINT GREEN (-4925 3000);
DISPLAY INVISIBLE (-4925 3000);
FORCEPROP 0 LAST PACK_TYPE C0201
J 2
(-5075 3000);
DISPLAY 0.680851 (-5075 3000);
DISPLAY INVISIBLE (-5075 3000);
FORCEPROP 1 LAST CDS_LMAN_SYM_OUTLINE -25,50,25,-50
J 2
(-4925 3000);
DISPLAY 0.468085 (-4925 3000);
PAINT GREEN (-4925 3000);
DISPLAY INVISIBLE (-4925 3000);
FORCEPROP 1 LAST PATH I141
J 2
(-4925 3000);
DISPLAY 0.723404 (-4925 3000);
DISPLAY INVISIBLE (-4925 3000);
FORCEPROP 2 LAST CDS_LIB pure_quanta
J 0
(-4925 3000);
DISPLAY INVISIBLE (-4925 3000);
FORCEADD Q_CAP_DIFFBUS..2
R 2
(-4925 2950);
FORCEPROP 1 LAST LOCATION C561
J 2
(-4725 2950);
DISPLAY 0.723404 (-4725 2950);
PAINT GREEN (-4725 2950);
FORCEPROP 0 LAST $SEC 1
J 0
(-4725 3000);
DISPLAY 0.680851 (-4725 3000);
PAINT MONO (-4725 3000);
DISPLAY INVISIBLE (-4725 3000);
FORCEPROP 0 LAST CDS_SEC 1
J 0
(-4725 3000);
DISPLAY 0.680851 (-4725 3000);
DISPLAY INVISIBLE (-4725 3000);
FORCEPROP 0 LASTPIN (-4850 2950) $PN 1
J 0
(-4840 2960);
DISPLAY 0.680851 (-4840 2960);
PAINT MONO (-4840 2960);
FORCEPROP 0 LASTPIN (-5000 2950) $PN 2
J 2
(-5010 2960);
DISPLAY 0.680851 (-5010 2960);
PAINT MONO (-5010 2960);
FORCEPROP 2 LAST VALUE DIFF BUS_0.22UF
J 2
(-5050 2950);
DISPLAY 0.553191 (-5050 2950);
FORCEPROP 0 LAST VOLTAGE 6.3V
J 2
(-5000 3125);
DISPLAY 0.680851 (-5000 3125);
DISPLAY INVISIBLE (-5000 3125);
FORCEPROP 0 LAST TOLERANCE 20%
J 2
(-5000 3075);
DISPLAY 0.680851 (-5000 3075);
DISPLAY INVISIBLE (-5000 3075);
FORCEPROP 1 LAST PART_NUMBER SP_CH4221MEE01
J 2
(-4900 3025);
DISPLAY 0.723404 (-4900 3025);
PAINT GREEN (-4900 3025);
DISPLAY INVISIBLE (-4900 3025);
FORCEPROP 1 LAST MATERIAL X6S
J 2
(-4775 3000);
DISPLAY 0.723404 (-4775 3000);
PAINT GREEN (-4775 3000);
DISPLAY INVISIBLE (-4775 3000);
FORCEPROP 1 LAST PIN_NAMES_ROTATE True
J 2
(-4925 2950);
DISPLAY 0.489362 (-4925 2950);
PAINT GREEN (-4925 2950);
DISPLAY INVISIBLE (-4925 2950);
FORCEPROP 0 LAST PACK_TYPE C0201
J 2
(-5075 2950);
DISPLAY 0.680851 (-5075 2950);
DISPLAY INVISIBLE (-5075 2950);
FORCEPROP 1 LAST CDS_LMAN_SYM_OUTLINE -25,50,25,-50
J 2
(-4925 2950);
DISPLAY 0.468085 (-4925 2950);
PAINT GREEN (-4925 2950);
DISPLAY INVISIBLE (-4925 2950);
FORCEPROP 1 LAST PATH I142
J 2
(-4925 2950);
DISPLAY 0.723404 (-4925 2950);
DISPLAY INVISIBLE (-4925 2950);
FORCEPROP 2 LAST CDS_LIB pure_quanta
J 0
(-4925 2950);
DISPLAY INVISIBLE (-4925 2950);
FORCEADD Q_CAP_DIFFBUS..2
R 2
(-4925 2900);
FORCEPROP 1 LAST LOCATION C562
J 2
(-4725 2900);
DISPLAY 0.723404 (-4725 2900);
PAINT GREEN (-4725 2900);
FORCEPROP 0 LAST $SEC 1
J 0
(-4725 2950);
DISPLAY 0.680851 (-4725 2950);
PAINT MONO (-4725 2950);
DISPLAY INVISIBLE (-4725 2950);
FORCEPROP 0 LAST CDS_SEC 1
J 0
(-4725 2950);
DISPLAY 0.680851 (-4725 2950);
DISPLAY INVISIBLE (-4725 2950);
FORCEPROP 0 LASTPIN (-4850 2900) $PN 1
J 0
(-4840 2910);
DISPLAY 0.680851 (-4840 2910);
PAINT MONO (-4840 2910);
FORCEPROP 0 LASTPIN (-5000 2900) $PN 2
J 2
(-5010 2910);
DISPLAY 0.680851 (-5010 2910);
PAINT MONO (-5010 2910);
FORCEPROP 2 LAST VALUE DIFF BUS_0.22UF
J 2
(-5050 2900);
DISPLAY 0.553191 (-5050 2900);
FORCEPROP 0 LAST PACK_TYPE C0201
J 2
(-5075 2900);
DISPLAY 0.680851 (-5075 2900);
DISPLAY INVISIBLE (-5075 2900);
FORCEPROP 1 LAST PIN_NAMES_ROTATE True
J 2
(-4925 2900);
DISPLAY 0.489362 (-4925 2900);
PAINT GREEN (-4925 2900);
DISPLAY INVISIBLE (-4925 2900);
FORCEPROP 1 LAST MATERIAL X6S
J 2
(-4775 2950);
DISPLAY 0.723404 (-4775 2950);
PAINT GREEN (-4775 2950);
DISPLAY INVISIBLE (-4775 2950);
FORCEPROP 1 LAST PART_NUMBER SP_CH4221MEE01
J 2
(-4900 2975);
DISPLAY 0.723404 (-4900 2975);
PAINT GREEN (-4900 2975);
DISPLAY INVISIBLE (-4900 2975);
FORCEPROP 0 LAST TOLERANCE 20%
J 2
(-5000 3025);
DISPLAY 0.680851 (-5000 3025);
DISPLAY INVISIBLE (-5000 3025);
FORCEPROP 0 LAST VOLTAGE 6.3V
J 2
(-5000 3075);
DISPLAY 0.680851 (-5000 3075);
DISPLAY INVISIBLE (-5000 3075);
FORCEPROP 1 LAST CDS_LMAN_SYM_OUTLINE -25,50,25,-50
J 2
(-4925 2900);
DISPLAY 0.468085 (-4925 2900);
PAINT GREEN (-4925 2900);
DISPLAY INVISIBLE (-4925 2900);
FORCEPROP 1 LAST PATH I143
J 2
(-4925 2900);
DISPLAY 0.723404 (-4925 2900);
DISPLAY INVISIBLE (-4925 2900);
FORCEPROP 2 LAST CDS_LIB pure_quanta
J 0
(-4925 2900);
DISPLAY INVISIBLE (-4925 2900);
FORCEADD Q_CAP_DIFFBUS..2
R 2
(-4925 2850);
FORCEPROP 1 LAST LOCATION C563
J 2
(-4725 2850);
DISPLAY 0.723404 (-4725 2850);
PAINT GREEN (-4725 2850);
FORCEPROP 0 LAST $SEC 1
J 0
(-4725 2900);
DISPLAY 0.680851 (-4725 2900);
PAINT MONO (-4725 2900);
DISPLAY INVISIBLE (-4725 2900);
FORCEPROP 0 LAST CDS_SEC 1
J 0
(-4725 2900);
DISPLAY 0.680851 (-4725 2900);
DISPLAY INVISIBLE (-4725 2900);
FORCEPROP 0 LASTPIN (-4850 2850) $PN 1
J 0
(-4840 2860);
DISPLAY 0.680851 (-4840 2860);
PAINT MONO (-4840 2860);
FORCEPROP 0 LASTPIN (-5000 2850) $PN 2
J 2
(-5010 2860);
DISPLAY 0.680851 (-5010 2860);
PAINT MONO (-5010 2860);
FORCEPROP 2 LAST VALUE DIFF BUS_0.22UF
J 2
(-5050 2850);
DISPLAY 0.553191 (-5050 2850);
FORCEPROP 0 LAST PACK_TYPE C0201
J 2
(-5075 2850);
DISPLAY 0.680851 (-5075 2850);
DISPLAY INVISIBLE (-5075 2850);
FORCEPROP 1 LAST PIN_NAMES_ROTATE True
J 2
(-4925 2850);
DISPLAY 0.489362 (-4925 2850);
PAINT GREEN (-4925 2850);
DISPLAY INVISIBLE (-4925 2850);
FORCEPROP 1 LAST MATERIAL X6S
J 2
(-4775 2900);
DISPLAY 0.723404 (-4775 2900);
PAINT GREEN (-4775 2900);
DISPLAY INVISIBLE (-4775 2900);
FORCEPROP 1 LAST PART_NUMBER SP_CH4221MEE01
J 2
(-4900 2925);
DISPLAY 0.723404 (-4900 2925);
PAINT GREEN (-4900 2925);
DISPLAY INVISIBLE (-4900 2925);
FORCEPROP 0 LAST TOLERANCE 20%
J 2
(-5000 2975);
DISPLAY 0.680851 (-5000 2975);
DISPLAY INVISIBLE (-5000 2975);
FORCEPROP 0 LAST VOLTAGE 6.3V
J 2
(-5000 3025);
DISPLAY 0.680851 (-5000 3025);
DISPLAY INVISIBLE (-5000 3025);
FORCEPROP 1 LAST CDS_LMAN_SYM_OUTLINE -25,50,25,-50
J 2
(-4925 2850);
DISPLAY 0.468085 (-4925 2850);
PAINT GREEN (-4925 2850);
DISPLAY INVISIBLE (-4925 2850);
FORCEPROP 1 LAST PATH I144
J 2
(-4925 2850);
DISPLAY 0.723404 (-4925 2850);
DISPLAY INVISIBLE (-4925 2850);
FORCEPROP 2 LAST CDS_LIB pure_quanta
J 0
(-4925 2850);
DISPLAY INVISIBLE (-4925 2850);
FORCEADD Q_CAP_DIFFBUS..2
R 2
(-4925 2800);
FORCEPROP 1 LAST LOCATION C564
J 2
(-4725 2800);
DISPLAY 0.723404 (-4725 2800);
PAINT GREEN (-4725 2800);
FORCEPROP 0 LAST $SEC 1
J 0
(-4725 2850);
DISPLAY 0.680851 (-4725 2850);
PAINT MONO (-4725 2850);
DISPLAY INVISIBLE (-4725 2850);
FORCEPROP 0 LAST CDS_SEC 1
J 0
(-4725 2850);
DISPLAY 0.680851 (-4725 2850);
DISPLAY INVISIBLE (-4725 2850);
FORCEPROP 0 LASTPIN (-4850 2800) $PN 1
J 0
(-4840 2810);
DISPLAY 0.680851 (-4840 2810);
PAINT MONO (-4840 2810);
FORCEPROP 0 LASTPIN (-5000 2800) $PN 2
J 2
(-5010 2810);
DISPLAY 0.680851 (-5010 2810);
PAINT MONO (-5010 2810);
FORCEPROP 2 LAST VALUE DIFF BUS_0.22UF
J 2
(-5050 2800);
DISPLAY 0.553191 (-5050 2800);
FORCEPROP 0 LAST VOLTAGE 6.3V
J 2
(-5000 2975);
DISPLAY 0.680851 (-5000 2975);
DISPLAY INVISIBLE (-5000 2975);
FORCEPROP 0 LAST TOLERANCE 20%
J 2
(-5000 2925);
DISPLAY 0.680851 (-5000 2925);
DISPLAY INVISIBLE (-5000 2925);
FORCEPROP 1 LAST PART_NUMBER SP_CH4221MEE01
J 2
(-4900 2875);
DISPLAY 0.723404 (-4900 2875);
PAINT GREEN (-4900 2875);
DISPLAY INVISIBLE (-4900 2875);
FORCEPROP 1 LAST MATERIAL X6S
J 2
(-4775 2850);
DISPLAY 0.723404 (-4775 2850);
PAINT GREEN (-4775 2850);
DISPLAY INVISIBLE (-4775 2850);
FORCEPROP 1 LAST PIN_NAMES_ROTATE True
J 2
(-4925 2800);
DISPLAY 0.489362 (-4925 2800);
PAINT GREEN (-4925 2800);
DISPLAY INVISIBLE (-4925 2800);
FORCEPROP 0 LAST PACK_TYPE C0201
J 2
(-5075 2800);
DISPLAY 0.680851 (-5075 2800);
DISPLAY INVISIBLE (-5075 2800);
FORCEPROP 1 LAST CDS_LMAN_SYM_OUTLINE -25,50,25,-50
J 2
(-4925 2800);
DISPLAY 0.468085 (-4925 2800);
PAINT GREEN (-4925 2800);
DISPLAY INVISIBLE (-4925 2800);
FORCEPROP 1 LAST PATH I145
J 2
(-4925 2800);
DISPLAY 0.723404 (-4925 2800);
DISPLAY INVISIBLE (-4925 2800);
FORCEPROP 2 LAST CDS_LIB pure_quanta
J 0
(-4925 2800);
DISPLAY INVISIBLE (-4925 2800);
FORCEADD Q_CAP_DIFFBUS..2
R 2
(-4925 2750);
FORCEPROP 1 LAST LOCATION C565
J 2
(-4725 2750);
DISPLAY 0.723404 (-4725 2750);
PAINT GREEN (-4725 2750);
FORCEPROP 0 LAST $SEC 1
J 0
(-4725 2800);
DISPLAY 0.680851 (-4725 2800);
PAINT MONO (-4725 2800);
DISPLAY INVISIBLE (-4725 2800);
FORCEPROP 0 LAST CDS_SEC 1
J 0
(-4725 2800);
DISPLAY 0.680851 (-4725 2800);
DISPLAY INVISIBLE (-4725 2800);
FORCEPROP 0 LASTPIN (-4850 2750) $PN 1
J 0
(-4840 2760);
DISPLAY 0.680851 (-4840 2760);
PAINT MONO (-4840 2760);
FORCEPROP 0 LASTPIN (-5000 2750) $PN 2
J 2
(-5010 2760);
DISPLAY 0.680851 (-5010 2760);
PAINT MONO (-5010 2760);
FORCEPROP 2 LAST VALUE DIFF BUS_0.22UF
J 2
(-5050 2750);
DISPLAY 0.553191 (-5050 2750);
FORCEPROP 0 LAST PACK_TYPE C0201
J 2
(-5075 2750);
DISPLAY 0.680851 (-5075 2750);
DISPLAY INVISIBLE (-5075 2750);
FORCEPROP 1 LAST PIN_NAMES_ROTATE True
J 2
(-4925 2750);
DISPLAY 0.489362 (-4925 2750);
PAINT GREEN (-4925 2750);
DISPLAY INVISIBLE (-4925 2750);
FORCEPROP 1 LAST MATERIAL X6S
J 2
(-4775 2800);
DISPLAY 0.723404 (-4775 2800);
PAINT GREEN (-4775 2800);
DISPLAY INVISIBLE (-4775 2800);
FORCEPROP 1 LAST PART_NUMBER SP_CH4221MEE01
J 2
(-4900 2825);
DISPLAY 0.723404 (-4900 2825);
PAINT GREEN (-4900 2825);
DISPLAY INVISIBLE (-4900 2825);
FORCEPROP 0 LAST TOLERANCE 20%
J 2
(-5000 2875);
DISPLAY 0.680851 (-5000 2875);
DISPLAY INVISIBLE (-5000 2875);
FORCEPROP 0 LAST VOLTAGE 6.3V
J 2
(-5000 2925);
DISPLAY 0.680851 (-5000 2925);
DISPLAY INVISIBLE (-5000 2925);
FORCEPROP 1 LAST CDS_LMAN_SYM_OUTLINE -25,50,25,-50
J 2
(-4925 2750);
DISPLAY 0.468085 (-4925 2750);
PAINT GREEN (-4925 2750);
DISPLAY INVISIBLE (-4925 2750);
FORCEPROP 1 LAST PATH I146
J 2
(-4925 2750);
DISPLAY 0.723404 (-4925 2750);
DISPLAY INVISIBLE (-4925 2750);
FORCEPROP 2 LAST CDS_LIB pure_quanta
J 0
(-4925 2750);
DISPLAY INVISIBLE (-4925 2750);
FORCEADD Q_CAP_DIFFBUS..2
R 2
(-4925 2700);
FORCEPROP 1 LAST LOCATION C566
J 2
(-4725 2700);
DISPLAY 0.723404 (-4725 2700);
PAINT GREEN (-4725 2700);
FORCEPROP 0 LAST $SEC 1
J 0
(-4725 2750);
DISPLAY 0.680851 (-4725 2750);
PAINT MONO (-4725 2750);
DISPLAY INVISIBLE (-4725 2750);
FORCEPROP 0 LAST CDS_SEC 1
J 0
(-4725 2750);
DISPLAY 0.680851 (-4725 2750);
DISPLAY INVISIBLE (-4725 2750);
FORCEPROP 0 LASTPIN (-4850 2700) $PN 1
J 0
(-4840 2710);
DISPLAY 0.680851 (-4840 2710);
PAINT MONO (-4840 2710);
FORCEPROP 0 LASTPIN (-5000 2700) $PN 2
J 2
(-5010 2710);
DISPLAY 0.680851 (-5010 2710);
PAINT MONO (-5010 2710);
FORCEPROP 2 LAST VALUE DIFF BUS_0.22UF
J 2
(-5050 2700);
DISPLAY 0.553191 (-5050 2700);
FORCEPROP 0 LAST PACK_TYPE C0201
J 2
(-5075 2700);
DISPLAY 0.680851 (-5075 2700);
DISPLAY INVISIBLE (-5075 2700);
FORCEPROP 1 LAST PIN_NAMES_ROTATE True
J 2
(-4925 2700);
DISPLAY 0.489362 (-4925 2700);
PAINT GREEN (-4925 2700);
DISPLAY INVISIBLE (-4925 2700);
FORCEPROP 1 LAST MATERIAL X6S
J 2
(-4775 2750);
DISPLAY 0.723404 (-4775 2750);
PAINT GREEN (-4775 2750);
DISPLAY INVISIBLE (-4775 2750);
FORCEPROP 1 LAST PART_NUMBER SP_CH4221MEE01
J 2
(-4900 2775);
DISPLAY 0.723404 (-4900 2775);
PAINT GREEN (-4900 2775);
DISPLAY INVISIBLE (-4900 2775);
FORCEPROP 0 LAST TOLERANCE 20%
J 2
(-5000 2825);
DISPLAY 0.680851 (-5000 2825);
DISPLAY INVISIBLE (-5000 2825);
FORCEPROP 0 LAST VOLTAGE 6.3V
J 2
(-5000 2875);
DISPLAY 0.680851 (-5000 2875);
DISPLAY INVISIBLE (-5000 2875);
FORCEPROP 1 LAST CDS_LMAN_SYM_OUTLINE -25,50,25,-50
J 2
(-4925 2700);
DISPLAY 0.468085 (-4925 2700);
PAINT GREEN (-4925 2700);
DISPLAY INVISIBLE (-4925 2700);
FORCEPROP 1 LAST PATH I147
J 2
(-4925 2700);
DISPLAY 0.723404 (-4925 2700);
DISPLAY INVISIBLE (-4925 2700);
FORCEPROP 2 LAST CDS_LIB pure_quanta
J 0
(-4925 2700);
DISPLAY INVISIBLE (-4925 2700);
FORCEADD Q_CAP_DIFFBUS..2
R 2
(-4925 2650);
FORCEPROP 1 LAST LOCATION C567
J 2
(-4725 2650);
DISPLAY 0.723404 (-4725 2650);
PAINT GREEN (-4725 2650);
FORCEPROP 0 LAST $SEC 1
J 0
(-4725 2700);
DISPLAY 0.680851 (-4725 2700);
PAINT MONO (-4725 2700);
DISPLAY INVISIBLE (-4725 2700);
FORCEPROP 0 LAST CDS_SEC 1
J 0
(-4725 2700);
DISPLAY 0.680851 (-4725 2700);
DISPLAY INVISIBLE (-4725 2700);
FORCEPROP 0 LASTPIN (-4850 2650) $PN 1
J 0
(-4840 2660);
DISPLAY 0.680851 (-4840 2660);
PAINT MONO (-4840 2660);
FORCEPROP 0 LASTPIN (-5000 2650) $PN 2
J 2
(-5010 2660);
DISPLAY 0.680851 (-5010 2660);
PAINT MONO (-5010 2660);
FORCEPROP 2 LAST VALUE DIFF BUS_0.22UF
J 2
(-5050 2650);
DISPLAY 0.553191 (-5050 2650);
FORCEPROP 0 LAST PACK_TYPE C0201
J 2
(-5075 2650);
DISPLAY 0.680851 (-5075 2650);
DISPLAY INVISIBLE (-5075 2650);
FORCEPROP 1 LAST PIN_NAMES_ROTATE True
J 2
(-4925 2650);
DISPLAY 0.489362 (-4925 2650);
PAINT GREEN (-4925 2650);
DISPLAY INVISIBLE (-4925 2650);
FORCEPROP 1 LAST MATERIAL X6S
J 2
(-4775 2700);
DISPLAY 0.723404 (-4775 2700);
PAINT GREEN (-4775 2700);
DISPLAY INVISIBLE (-4775 2700);
FORCEPROP 1 LAST PART_NUMBER SP_CH4221MEE01
J 2
(-4900 2725);
DISPLAY 0.723404 (-4900 2725);
PAINT GREEN (-4900 2725);
DISPLAY INVISIBLE (-4900 2725);
FORCEPROP 0 LAST TOLERANCE 20%
J 2
(-5000 2775);
DISPLAY 0.680851 (-5000 2775);
DISPLAY INVISIBLE (-5000 2775);
FORCEPROP 0 LAST VOLTAGE 6.3V
J 2
(-5000 2825);
DISPLAY 0.680851 (-5000 2825);
DISPLAY INVISIBLE (-5000 2825);
FORCEPROP 1 LAST CDS_LMAN_SYM_OUTLINE -25,50,25,-50
J 2
(-4925 2650);
DISPLAY 0.468085 (-4925 2650);
PAINT GREEN (-4925 2650);
DISPLAY INVISIBLE (-4925 2650);
FORCEPROP 1 LAST PATH I148
J 2
(-4925 2650);
DISPLAY 0.723404 (-4925 2650);
DISPLAY INVISIBLE (-4925 2650);
FORCEPROP 2 LAST CDS_LIB pure_quanta
J 0
(-4925 2650);
DISPLAY INVISIBLE (-4925 2650);
FORCEADD Q_CAP_DIFFBUS..2
R 2
(-4925 2600);
FORCEPROP 1 LAST LOCATION C568
J 2
(-4725 2600);
DISPLAY 0.723404 (-4725 2600);
PAINT GREEN (-4725 2600);
FORCEPROP 0 LAST $SEC 1
J 0
(-4725 2650);
DISPLAY 0.680851 (-4725 2650);
PAINT MONO (-4725 2650);
DISPLAY INVISIBLE (-4725 2650);
FORCEPROP 0 LAST CDS_SEC 1
J 0
(-4725 2650);
DISPLAY 0.680851 (-4725 2650);
DISPLAY INVISIBLE (-4725 2650);
FORCEPROP 0 LASTPIN (-4850 2600) $PN 1
J 0
(-4840 2610);
DISPLAY 0.680851 (-4840 2610);
PAINT MONO (-4840 2610);
FORCEPROP 0 LASTPIN (-5000 2600) $PN 2
J 2
(-5010 2610);
DISPLAY 0.680851 (-5010 2610);
PAINT MONO (-5010 2610);
FORCEPROP 2 LAST VALUE DIFF BUS_0.22UF
J 2
(-5050 2600);
DISPLAY 0.553191 (-5050 2600);
FORCEPROP 0 LAST PACK_TYPE C0201
J 2
(-5075 2600);
DISPLAY 0.680851 (-5075 2600);
DISPLAY INVISIBLE (-5075 2600);
FORCEPROP 1 LAST PIN_NAMES_ROTATE True
J 2
(-4925 2600);
DISPLAY 0.489362 (-4925 2600);
PAINT GREEN (-4925 2600);
DISPLAY INVISIBLE (-4925 2600);
FORCEPROP 1 LAST MATERIAL X6S
J 2
(-4775 2650);
DISPLAY 0.723404 (-4775 2650);
PAINT GREEN (-4775 2650);
DISPLAY INVISIBLE (-4775 2650);
FORCEPROP 1 LAST PART_NUMBER SP_CH4221MEE01
J 2
(-4900 2675);
DISPLAY 0.723404 (-4900 2675);
PAINT GREEN (-4900 2675);
DISPLAY INVISIBLE (-4900 2675);
FORCEPROP 0 LAST TOLERANCE 20%
J 2
(-5000 2725);
DISPLAY 0.680851 (-5000 2725);
DISPLAY INVISIBLE (-5000 2725);
FORCEPROP 0 LAST VOLTAGE 6.3V
J 2
(-5000 2775);
DISPLAY 0.680851 (-5000 2775);
DISPLAY INVISIBLE (-5000 2775);
FORCEPROP 1 LAST CDS_LMAN_SYM_OUTLINE -25,50,25,-50
J 2
(-4925 2600);
DISPLAY 0.468085 (-4925 2600);
PAINT GREEN (-4925 2600);
DISPLAY INVISIBLE (-4925 2600);
FORCEPROP 1 LAST PATH I149
J 2
(-4925 2600);
DISPLAY 0.723404 (-4925 2600);
DISPLAY INVISIBLE (-4925 2600);
FORCEPROP 2 LAST CDS_LIB pure_quanta
J 0
(-4925 2600);
DISPLAY INVISIBLE (-4925 2600);
FORCEADD TAP..6
(-5800 5150);
FORCEPROP 3 LASTPIN (-5750 5150) SIG_NAME P5E_CPU0_P0_TX_DN<6>
J 0
(-5740 5160);
DISPLAY 0.659574 (-5740 5160);
PAINT MONO (-5740 5160);
DISPLAY INVISIBLE (-5740 5160);
FORCEPROP 1 LASTPIN (-5750 5150) BN 6
J 0
(-5802 5158);
DISPLAY 0.680851 (-5802 5158);
PAINT MONO (-5802 5158);
FORCEPROP 2 LAST CDS_LIB standard
J 0
(-5800 5150);
DISPLAY INVISIBLE (-5800 5150);
FORCEPROP 1 LAST PATH I15
J 0
(-5802 5150);
DISPLAY 0.872340 (-5802 5150);
PAINT GREEN (-5802 5150);
DISPLAY INVISIBLE (-5802 5150);
FORCEPROP 1 LAST BODY_TYPE PLUMBING
J 0
(-5800 5100);
DISPLAY 0.574468 (-5800 5100);
PAINT GREEN (-5800 5100);
DISPLAY INVISIBLE (-5800 5100);
FORCEPROP 1 LAST HDL_TAP TRUE
J 0
(-5475 5025);
DISPLAY 0.574468 (-5475 5025);
PAINT GREEN (-5475 5025);
DISPLAY INVISIBLE (-5475 5025);
FORCEADD Q_CAP_DIFFBUS..2
R 2
(-4925 2500);
FORCEPROP 1 LAST LOCATION C570
J 2
(-4725 2500);
DISPLAY 0.723404 (-4725 2500);
PAINT GREEN (-4725 2500);
FORCEPROP 0 LAST $SEC 1
J 0
(-4725 2550);
DISPLAY 0.680851 (-4725 2550);
PAINT MONO (-4725 2550);
DISPLAY INVISIBLE (-4725 2550);
FORCEPROP 0 LAST CDS_SEC 1
J 0
(-4725 2550);
DISPLAY 0.680851 (-4725 2550);
DISPLAY INVISIBLE (-4725 2550);
FORCEPROP 0 LASTPIN (-4850 2500) $PN 1
J 0
(-4840 2510);
DISPLAY 0.680851 (-4840 2510);
PAINT MONO (-4840 2510);
FORCEPROP 0 LASTPIN (-5000 2500) $PN 2
J 2
(-5010 2510);
DISPLAY 0.680851 (-5010 2510);
PAINT MONO (-5010 2510);
FORCEPROP 2 LAST VALUE DIFF BUS_0.22UF
J 2
(-5050 2500);
DISPLAY 0.553191 (-5050 2500);
FORCEPROP 0 LAST PACK_TYPE C0201
J 2
(-5075 2500);
DISPLAY 0.680851 (-5075 2500);
DISPLAY INVISIBLE (-5075 2500);
FORCEPROP 1 LAST PIN_NAMES_ROTATE True
J 2
(-4925 2500);
DISPLAY 0.489362 (-4925 2500);
PAINT GREEN (-4925 2500);
DISPLAY INVISIBLE (-4925 2500);
FORCEPROP 1 LAST MATERIAL X6S
J 2
(-4775 2550);
DISPLAY 0.723404 (-4775 2550);
PAINT GREEN (-4775 2550);
DISPLAY INVISIBLE (-4775 2550);
FORCEPROP 1 LAST PART_NUMBER SP_CH4221MEE01
J 2
(-4900 2575);
DISPLAY 0.723404 (-4900 2575);
PAINT GREEN (-4900 2575);
DISPLAY INVISIBLE (-4900 2575);
FORCEPROP 0 LAST TOLERANCE 20%
J 2
(-5000 2625);
DISPLAY 0.680851 (-5000 2625);
DISPLAY INVISIBLE (-5000 2625);
FORCEPROP 0 LAST VOLTAGE 6.3V
J 2
(-5000 2675);
DISPLAY 0.680851 (-5000 2675);
DISPLAY INVISIBLE (-5000 2675);
FORCEPROP 1 LAST CDS_LMAN_SYM_OUTLINE -25,50,25,-50
J 2
(-4925 2500);
DISPLAY 0.468085 (-4925 2500);
PAINT GREEN (-4925 2500);
DISPLAY INVISIBLE (-4925 2500);
FORCEPROP 1 LAST PATH I150
J 2
(-4925 2500);
DISPLAY 0.723404 (-4925 2500);
DISPLAY INVISIBLE (-4925 2500);
FORCEPROP 2 LAST CDS_LIB pure_quanta
J 0
(-4925 2500);
DISPLAY INVISIBLE (-4925 2500);
FORCEADD Q_CAP_DIFFBUS..2
R 2
(-4925 2550);
FORCEPROP 1 LAST LOCATION C569
J 2
(-4725 2550);
DISPLAY 0.723404 (-4725 2550);
PAINT GREEN (-4725 2550);
FORCEPROP 0 LAST $SEC 1
J 0
(-4725 2600);
DISPLAY 0.680851 (-4725 2600);
PAINT MONO (-4725 2600);
DISPLAY INVISIBLE (-4725 2600);
FORCEPROP 0 LAST CDS_SEC 1
J 0
(-4725 2600);
DISPLAY 0.680851 (-4725 2600);
DISPLAY INVISIBLE (-4725 2600);
FORCEPROP 0 LASTPIN (-4850 2550) $PN 1
J 0
(-4840 2560);
DISPLAY 0.680851 (-4840 2560);
PAINT MONO (-4840 2560);
FORCEPROP 0 LASTPIN (-5000 2550) $PN 2
J 2
(-5010 2560);
DISPLAY 0.680851 (-5010 2560);
PAINT MONO (-5010 2560);
FORCEPROP 2 LAST VALUE DIFF BUS_0.22UF
J 2
(-5050 2550);
DISPLAY 0.553191 (-5050 2550);
FORCEPROP 0 LAST PACK_TYPE C0201
J 2
(-5075 2550);
DISPLAY 0.680851 (-5075 2550);
DISPLAY INVISIBLE (-5075 2550);
FORCEPROP 1 LAST PIN_NAMES_ROTATE True
J 2
(-4925 2550);
DISPLAY 0.489362 (-4925 2550);
PAINT GREEN (-4925 2550);
DISPLAY INVISIBLE (-4925 2550);
FORCEPROP 1 LAST MATERIAL X6S
J 2
(-4775 2600);
DISPLAY 0.723404 (-4775 2600);
PAINT GREEN (-4775 2600);
DISPLAY INVISIBLE (-4775 2600);
FORCEPROP 1 LAST PART_NUMBER SP_CH4221MEE01
J 2
(-4900 2625);
DISPLAY 0.723404 (-4900 2625);
PAINT GREEN (-4900 2625);
DISPLAY INVISIBLE (-4900 2625);
FORCEPROP 0 LAST TOLERANCE 20%
J 2
(-5000 2675);
DISPLAY 0.680851 (-5000 2675);
DISPLAY INVISIBLE (-5000 2675);
FORCEPROP 0 LAST VOLTAGE 6.3V
J 2
(-5000 2725);
DISPLAY 0.680851 (-5000 2725);
DISPLAY INVISIBLE (-5000 2725);
FORCEPROP 1 LAST CDS_LMAN_SYM_OUTLINE -25,50,25,-50
J 2
(-4925 2550);
DISPLAY 0.468085 (-4925 2550);
PAINT GREEN (-4925 2550);
DISPLAY INVISIBLE (-4925 2550);
FORCEPROP 1 LAST PATH I151
J 2
(-4925 2550);
DISPLAY 0.723404 (-4925 2550);
DISPLAY INVISIBLE (-4925 2550);
FORCEPROP 2 LAST CDS_LIB pure_quanta
J 0
(-4925 2550);
DISPLAY INVISIBLE (-4925 2550);
FORCEADD Q_CAP_DIFFBUS..2
R 2
(-4925 2450);
FORCEPROP 1 LAST LOCATION C571
J 2
(-4725 2450);
DISPLAY 0.723404 (-4725 2450);
PAINT GREEN (-4725 2450);
FORCEPROP 0 LAST $SEC 1
J 0
(-4725 2500);
DISPLAY 0.680851 (-4725 2500);
PAINT MONO (-4725 2500);
DISPLAY INVISIBLE (-4725 2500);
FORCEPROP 0 LAST CDS_SEC 1
J 0
(-4725 2500);
DISPLAY 0.680851 (-4725 2500);
DISPLAY INVISIBLE (-4725 2500);
FORCEPROP 0 LASTPIN (-4850 2450) $PN 1
J 0
(-4840 2460);
DISPLAY 0.680851 (-4840 2460);
PAINT MONO (-4840 2460);
FORCEPROP 0 LASTPIN (-5000 2450) $PN 2
J 2
(-5010 2460);
DISPLAY 0.680851 (-5010 2460);
PAINT MONO (-5010 2460);
FORCEPROP 2 LAST VALUE DIFF BUS_0.22UF
J 2
(-5050 2450);
DISPLAY 0.553191 (-5050 2450);
FORCEPROP 0 LAST VOLTAGE 6.3V
J 2
(-5000 2625);
DISPLAY 0.680851 (-5000 2625);
DISPLAY INVISIBLE (-5000 2625);
FORCEPROP 0 LAST TOLERANCE 20%
J 2
(-5000 2575);
DISPLAY 0.680851 (-5000 2575);
DISPLAY INVISIBLE (-5000 2575);
FORCEPROP 1 LAST PART_NUMBER SP_CH4221MEE01
J 2
(-4900 2525);
DISPLAY 0.723404 (-4900 2525);
PAINT GREEN (-4900 2525);
DISPLAY INVISIBLE (-4900 2525);
FORCEPROP 1 LAST MATERIAL X6S
J 2
(-4775 2500);
DISPLAY 0.723404 (-4775 2500);
PAINT GREEN (-4775 2500);
DISPLAY INVISIBLE (-4775 2500);
FORCEPROP 1 LAST PIN_NAMES_ROTATE True
J 2
(-4925 2450);
DISPLAY 0.489362 (-4925 2450);
PAINT GREEN (-4925 2450);
DISPLAY INVISIBLE (-4925 2450);
FORCEPROP 0 LAST PACK_TYPE C0201
J 2
(-5075 2450);
DISPLAY 0.680851 (-5075 2450);
DISPLAY INVISIBLE (-5075 2450);
FORCEPROP 1 LAST CDS_LMAN_SYM_OUTLINE -25,50,25,-50
J 2
(-4925 2450);
DISPLAY 0.468085 (-4925 2450);
PAINT GREEN (-4925 2450);
DISPLAY INVISIBLE (-4925 2450);
FORCEPROP 1 LAST PATH I152
J 2
(-4925 2450);
DISPLAY 0.723404 (-4925 2450);
DISPLAY INVISIBLE (-4925 2450);
FORCEPROP 2 LAST CDS_LIB pure_quanta
J 0
(-4925 2450);
DISPLAY INVISIBLE (-4925 2450);
FORCEADD Q_CAP_DIFFBUS..2
R 2
(-4925 2400);
FORCEPROP 1 LAST LOCATION C572
J 2
(-4725 2400);
DISPLAY 0.723404 (-4725 2400);
PAINT GREEN (-4725 2400);
FORCEPROP 0 LAST $SEC 1
J 0
(-4725 2450);
DISPLAY 0.680851 (-4725 2450);
PAINT MONO (-4725 2450);
DISPLAY INVISIBLE (-4725 2450);
FORCEPROP 0 LAST CDS_SEC 1
J 0
(-4725 2450);
DISPLAY 0.680851 (-4725 2450);
DISPLAY INVISIBLE (-4725 2450);
FORCEPROP 0 LASTPIN (-4850 2400) $PN 1
J 0
(-4840 2410);
DISPLAY 0.680851 (-4840 2410);
PAINT MONO (-4840 2410);
FORCEPROP 0 LASTPIN (-5000 2400) $PN 2
J 2
(-5010 2410);
DISPLAY 0.680851 (-5010 2410);
PAINT MONO (-5010 2410);
FORCEPROP 2 LAST VALUE DIFF BUS_0.22UF
J 2
(-5050 2400);
DISPLAY 0.553191 (-5050 2400);
FORCEPROP 0 LAST PACK_TYPE C0201
J 2
(-5075 2400);
DISPLAY 0.680851 (-5075 2400);
DISPLAY INVISIBLE (-5075 2400);
FORCEPROP 1 LAST PIN_NAMES_ROTATE True
J 2
(-4925 2400);
DISPLAY 0.489362 (-4925 2400);
PAINT GREEN (-4925 2400);
DISPLAY INVISIBLE (-4925 2400);
FORCEPROP 1 LAST MATERIAL X6S
J 2
(-4775 2450);
DISPLAY 0.723404 (-4775 2450);
PAINT GREEN (-4775 2450);
DISPLAY INVISIBLE (-4775 2450);
FORCEPROP 1 LAST PART_NUMBER SP_CH4221MEE01
J 2
(-4900 2475);
DISPLAY 0.723404 (-4900 2475);
PAINT GREEN (-4900 2475);
DISPLAY INVISIBLE (-4900 2475);
FORCEPROP 0 LAST TOLERANCE 20%
J 2
(-5000 2525);
DISPLAY 0.680851 (-5000 2525);
DISPLAY INVISIBLE (-5000 2525);
FORCEPROP 0 LAST VOLTAGE 6.3V
J 2
(-5000 2575);
DISPLAY 0.680851 (-5000 2575);
DISPLAY INVISIBLE (-5000 2575);
FORCEPROP 1 LAST CDS_LMAN_SYM_OUTLINE -25,50,25,-50
J 2
(-4925 2400);
DISPLAY 0.468085 (-4925 2400);
PAINT GREEN (-4925 2400);
DISPLAY INVISIBLE (-4925 2400);
FORCEPROP 1 LAST PATH I153
J 2
(-4925 2400);
DISPLAY 0.723404 (-4925 2400);
DISPLAY INVISIBLE (-4925 2400);
FORCEPROP 2 LAST CDS_LIB pure_quanta
J 0
(-4925 2400);
DISPLAY INVISIBLE (-4925 2400);
FORCEADD Q_CAP_DIFFBUS..2
R 2
(-4925 2350);
FORCEPROP 1 LAST LOCATION C573
J 2
(-4725 2350);
DISPLAY 0.723404 (-4725 2350);
PAINT GREEN (-4725 2350);
FORCEPROP 0 LAST $SEC 1
J 0
(-4725 2400);
DISPLAY 0.680851 (-4725 2400);
PAINT MONO (-4725 2400);
DISPLAY INVISIBLE (-4725 2400);
FORCEPROP 0 LAST CDS_SEC 1
J 0
(-4725 2400);
DISPLAY 0.680851 (-4725 2400);
DISPLAY INVISIBLE (-4725 2400);
FORCEPROP 0 LASTPIN (-4850 2350) $PN 1
J 0
(-4840 2360);
DISPLAY 0.680851 (-4840 2360);
PAINT MONO (-4840 2360);
FORCEPROP 0 LASTPIN (-5000 2350) $PN 2
J 2
(-5010 2360);
DISPLAY 0.680851 (-5010 2360);
PAINT MONO (-5010 2360);
FORCEPROP 2 LAST VALUE DIFF BUS_0.22UF
J 2
(-5050 2350);
DISPLAY 0.553191 (-5050 2350);
FORCEPROP 0 LAST PACK_TYPE C0201
J 2
(-5075 2350);
DISPLAY 0.680851 (-5075 2350);
DISPLAY INVISIBLE (-5075 2350);
FORCEPROP 1 LAST PIN_NAMES_ROTATE True
J 2
(-4925 2350);
DISPLAY 0.489362 (-4925 2350);
PAINT GREEN (-4925 2350);
DISPLAY INVISIBLE (-4925 2350);
FORCEPROP 1 LAST MATERIAL X6S
J 2
(-4775 2400);
DISPLAY 0.723404 (-4775 2400);
PAINT GREEN (-4775 2400);
DISPLAY INVISIBLE (-4775 2400);
FORCEPROP 1 LAST PART_NUMBER SP_CH4221MEE01
J 2
(-4900 2425);
DISPLAY 0.723404 (-4900 2425);
PAINT GREEN (-4900 2425);
DISPLAY INVISIBLE (-4900 2425);
FORCEPROP 0 LAST TOLERANCE 20%
J 2
(-5000 2475);
DISPLAY 0.680851 (-5000 2475);
DISPLAY INVISIBLE (-5000 2475);
FORCEPROP 0 LAST VOLTAGE 6.3V
J 2
(-5000 2525);
DISPLAY 0.680851 (-5000 2525);
DISPLAY INVISIBLE (-5000 2525);
FORCEPROP 1 LAST CDS_LMAN_SYM_OUTLINE -25,50,25,-50
J 2
(-4925 2350);
DISPLAY 0.468085 (-4925 2350);
PAINT GREEN (-4925 2350);
DISPLAY INVISIBLE (-4925 2350);
FORCEPROP 1 LAST PATH I154
J 2
(-4925 2350);
DISPLAY 0.723404 (-4925 2350);
DISPLAY INVISIBLE (-4925 2350);
FORCEPROP 2 LAST CDS_LIB pure_quanta
J 0
(-4925 2350);
DISPLAY INVISIBLE (-4925 2350);
FORCEADD Q_CAP_DIFFBUS..2
R 2
(-4925 2250);
FORCEPROP 1 LAST LOCATION C575
J 2
(-4725 2250);
DISPLAY 0.723404 (-4725 2250);
PAINT GREEN (-4725 2250);
FORCEPROP 0 LAST $SEC 1
J 0
(-4725 2300);
DISPLAY 0.680851 (-4725 2300);
PAINT MONO (-4725 2300);
DISPLAY INVISIBLE (-4725 2300);
FORCEPROP 0 LAST CDS_SEC 1
J 0
(-4725 2300);
DISPLAY 0.680851 (-4725 2300);
DISPLAY INVISIBLE (-4725 2300);
FORCEPROP 0 LASTPIN (-4850 2250) $PN 1
J 0
(-4840 2260);
DISPLAY 0.680851 (-4840 2260);
PAINT MONO (-4840 2260);
FORCEPROP 0 LASTPIN (-5000 2250) $PN 2
J 2
(-5010 2260);
DISPLAY 0.680851 (-5010 2260);
PAINT MONO (-5010 2260);
FORCEPROP 2 LAST VALUE DIFF BUS_0.22UF
J 2
(-5050 2250);
DISPLAY 0.553191 (-5050 2250);
FORCEPROP 0 LAST VOLTAGE 6.3V
J 2
(-5000 2425);
DISPLAY 0.680851 (-5000 2425);
DISPLAY INVISIBLE (-5000 2425);
FORCEPROP 0 LAST TOLERANCE 20%
J 2
(-5000 2375);
DISPLAY 0.680851 (-5000 2375);
DISPLAY INVISIBLE (-5000 2375);
FORCEPROP 1 LAST PART_NUMBER SP_CH4221MEE01
J 2
(-4900 2325);
DISPLAY 0.723404 (-4900 2325);
PAINT GREEN (-4900 2325);
DISPLAY INVISIBLE (-4900 2325);
FORCEPROP 1 LAST MATERIAL X6S
J 2
(-4775 2300);
DISPLAY 0.723404 (-4775 2300);
PAINT GREEN (-4775 2300);
DISPLAY INVISIBLE (-4775 2300);
FORCEPROP 1 LAST PIN_NAMES_ROTATE True
J 2
(-4925 2250);
DISPLAY 0.489362 (-4925 2250);
PAINT GREEN (-4925 2250);
DISPLAY INVISIBLE (-4925 2250);
FORCEPROP 0 LAST PACK_TYPE C0201
J 2
(-5075 2250);
DISPLAY 0.680851 (-5075 2250);
DISPLAY INVISIBLE (-5075 2250);
FORCEPROP 1 LAST CDS_LMAN_SYM_OUTLINE -25,50,25,-50
J 2
(-4925 2250);
DISPLAY 0.468085 (-4925 2250);
PAINT GREEN (-4925 2250);
DISPLAY INVISIBLE (-4925 2250);
FORCEPROP 1 LAST PATH I155
J 2
(-4925 2250);
DISPLAY 0.723404 (-4925 2250);
DISPLAY INVISIBLE (-4925 2250);
FORCEPROP 2 LAST CDS_LIB pure_quanta
J 0
(-4925 2250);
DISPLAY INVISIBLE (-4925 2250);
FORCEADD Q_CAP_DIFFBUS..2
R 2
(-4925 2300);
FORCEPROP 1 LAST LOCATION C574
J 2
(-4700 2300);
DISPLAY 0.723404 (-4700 2300);
PAINT GREEN (-4700 2300);
FORCEPROP 0 LAST $SEC 1
J 0
(-4700 2350);
DISPLAY 0.680851 (-4700 2350);
PAINT MONO (-4700 2350);
DISPLAY INVISIBLE (-4700 2350);
FORCEPROP 0 LAST CDS_SEC 1
J 0
(-4700 2350);
DISPLAY 0.680851 (-4700 2350);
DISPLAY INVISIBLE (-4700 2350);
FORCEPROP 0 LASTPIN (-4850 2300) $PN 1
J 0
(-4840 2310);
DISPLAY 0.680851 (-4840 2310);
PAINT MONO (-4840 2310);
FORCEPROP 0 LASTPIN (-5000 2300) $PN 2
J 2
(-5010 2310);
DISPLAY 0.680851 (-5010 2310);
PAINT MONO (-5010 2310);
FORCEPROP 2 LAST VALUE DIFF BUS_0.22UF
J 2
(-5050 2300);
DISPLAY 0.553191 (-5050 2300);
FORCEPROP 0 LAST PACK_TYPE C0201
J 2
(-5075 2300);
DISPLAY 0.680851 (-5075 2300);
DISPLAY INVISIBLE (-5075 2300);
FORCEPROP 1 LAST PIN_NAMES_ROTATE True
J 2
(-4925 2300);
DISPLAY 0.489362 (-4925 2300);
PAINT GREEN (-4925 2300);
DISPLAY INVISIBLE (-4925 2300);
FORCEPROP 1 LAST MATERIAL X6S
J 2
(-4775 2350);
DISPLAY 0.723404 (-4775 2350);
PAINT GREEN (-4775 2350);
DISPLAY INVISIBLE (-4775 2350);
FORCEPROP 1 LAST PART_NUMBER SP_CH4221MEE01
J 2
(-4900 2375);
DISPLAY 0.723404 (-4900 2375);
PAINT GREEN (-4900 2375);
DISPLAY INVISIBLE (-4900 2375);
FORCEPROP 0 LAST TOLERANCE 20%
J 2
(-5000 2425);
DISPLAY 0.680851 (-5000 2425);
DISPLAY INVISIBLE (-5000 2425);
FORCEPROP 0 LAST VOLTAGE 6.3V
J 2
(-5000 2475);
DISPLAY 0.680851 (-5000 2475);
DISPLAY INVISIBLE (-5000 2475);
FORCEPROP 1 LAST CDS_LMAN_SYM_OUTLINE -25,50,25,-50
J 2
(-4925 2300);
DISPLAY 0.468085 (-4925 2300);
PAINT GREEN (-4925 2300);
DISPLAY INVISIBLE (-4925 2300);
FORCEPROP 1 LAST PATH I156
J 2
(-4925 2300);
DISPLAY 0.723404 (-4925 2300);
DISPLAY INVISIBLE (-4925 2300);
FORCEPROP 2 LAST CDS_LIB pure_quanta
J 0
(-4925 2300);
DISPLAY INVISIBLE (-4925 2300);
FORCEADD Q_CAP_DIFFBUS..2
R 2
(-4925 2200);
FORCEPROP 1 LAST LOCATION C576
J 2
(-4700 2200);
DISPLAY 0.723404 (-4700 2200);
PAINT GREEN (-4700 2200);
FORCEPROP 0 LAST $SEC 1
J 0
(-4700 2250);
DISPLAY 0.680851 (-4700 2250);
PAINT MONO (-4700 2250);
DISPLAY INVISIBLE (-4700 2250);
FORCEPROP 0 LAST CDS_SEC 1
J 0
(-4700 2250);
DISPLAY 0.680851 (-4700 2250);
DISPLAY INVISIBLE (-4700 2250);
FORCEPROP 0 LASTPIN (-4850 2200) $PN 1
J 0
(-4840 2210);
DISPLAY 0.680851 (-4840 2210);
PAINT MONO (-4840 2210);
FORCEPROP 0 LASTPIN (-5000 2200) $PN 2
J 2
(-5010 2210);
DISPLAY 0.680851 (-5010 2210);
PAINT MONO (-5010 2210);
FORCEPROP 2 LAST VALUE DIFF BUS_0.22UF
J 2
(-5050 2200);
DISPLAY 0.553191 (-5050 2200);
FORCEPROP 0 LAST PACK_TYPE C0201
J 2
(-5075 2200);
DISPLAY 0.680851 (-5075 2200);
DISPLAY INVISIBLE (-5075 2200);
FORCEPROP 1 LAST PIN_NAMES_ROTATE True
J 2
(-4925 2200);
DISPLAY 0.489362 (-4925 2200);
PAINT GREEN (-4925 2200);
DISPLAY INVISIBLE (-4925 2200);
FORCEPROP 1 LAST MATERIAL X6S
J 2
(-4775 2250);
DISPLAY 0.723404 (-4775 2250);
PAINT GREEN (-4775 2250);
DISPLAY INVISIBLE (-4775 2250);
FORCEPROP 1 LAST PART_NUMBER SP_CH4221MEE01
J 2
(-4900 2275);
DISPLAY 0.723404 (-4900 2275);
PAINT GREEN (-4900 2275);
DISPLAY INVISIBLE (-4900 2275);
FORCEPROP 0 LAST TOLERANCE 20%
J 2
(-5000 2325);
DISPLAY 0.680851 (-5000 2325);
DISPLAY INVISIBLE (-5000 2325);
FORCEPROP 0 LAST VOLTAGE 6.3V
J 2
(-5000 2375);
DISPLAY 0.680851 (-5000 2375);
DISPLAY INVISIBLE (-5000 2375);
FORCEPROP 1 LAST CDS_LMAN_SYM_OUTLINE -25,50,25,-50
J 2
(-4925 2200);
DISPLAY 0.468085 (-4925 2200);
PAINT GREEN (-4925 2200);
DISPLAY INVISIBLE (-4925 2200);
FORCEPROP 1 LAST PATH I157
J 2
(-4925 2200);
DISPLAY 0.723404 (-4925 2200);
DISPLAY INVISIBLE (-4925 2200);
FORCEPROP 2 LAST CDS_LIB pure_quanta
J 0
(-4925 2200);
DISPLAY INVISIBLE (-4925 2200);
FORCEADD Q_CAP_DIFFBUS..2
R 2
(-4925 2150);
FORCEPROP 1 LAST LOCATION C577
J 2
(-4700 2150);
DISPLAY 0.723404 (-4700 2150);
PAINT GREEN (-4700 2150);
FORCEPROP 0 LAST $SEC 1
J 0
(-4700 2200);
DISPLAY 0.680851 (-4700 2200);
PAINT MONO (-4700 2200);
DISPLAY INVISIBLE (-4700 2200);
FORCEPROP 0 LAST CDS_SEC 1
J 0
(-4700 2200);
DISPLAY 0.680851 (-4700 2200);
DISPLAY INVISIBLE (-4700 2200);
FORCEPROP 0 LASTPIN (-4850 2150) $PN 1
J 0
(-4840 2160);
DISPLAY 0.680851 (-4840 2160);
PAINT MONO (-4840 2160);
FORCEPROP 0 LASTPIN (-5000 2150) $PN 2
J 2
(-5010 2160);
DISPLAY 0.680851 (-5010 2160);
PAINT MONO (-5010 2160);
FORCEPROP 2 LAST VALUE DIFF BUS_0.22UF
J 2
(-5050 2150);
DISPLAY 0.553191 (-5050 2150);
FORCEPROP 0 LAST PACK_TYPE C0201
J 2
(-5075 2150);
DISPLAY 0.680851 (-5075 2150);
DISPLAY INVISIBLE (-5075 2150);
FORCEPROP 1 LAST PIN_NAMES_ROTATE True
J 2
(-4925 2150);
DISPLAY 0.489362 (-4925 2150);
PAINT GREEN (-4925 2150);
DISPLAY INVISIBLE (-4925 2150);
FORCEPROP 1 LAST MATERIAL X6S
J 2
(-4775 2200);
DISPLAY 0.723404 (-4775 2200);
PAINT GREEN (-4775 2200);
DISPLAY INVISIBLE (-4775 2200);
FORCEPROP 1 LAST PART_NUMBER SP_CH4221MEE01
J 2
(-4900 2225);
DISPLAY 0.723404 (-4900 2225);
PAINT GREEN (-4900 2225);
DISPLAY INVISIBLE (-4900 2225);
FORCEPROP 0 LAST TOLERANCE 20%
J 2
(-5000 2275);
DISPLAY 0.680851 (-5000 2275);
DISPLAY INVISIBLE (-5000 2275);
FORCEPROP 0 LAST VOLTAGE 6.3V
J 2
(-5000 2325);
DISPLAY 0.680851 (-5000 2325);
DISPLAY INVISIBLE (-5000 2325);
FORCEPROP 1 LAST CDS_LMAN_SYM_OUTLINE -25,50,25,-50
J 2
(-4925 2150);
DISPLAY 0.468085 (-4925 2150);
PAINT GREEN (-4925 2150);
DISPLAY INVISIBLE (-4925 2150);
FORCEPROP 1 LAST PATH I158
J 2
(-4925 2150);
DISPLAY 0.723404 (-4925 2150);
DISPLAY INVISIBLE (-4925 2150);
FORCEPROP 2 LAST CDS_LIB pure_quanta
J 0
(-4925 2150);
DISPLAY INVISIBLE (-4925 2150);
FORCEADD Q_CAP_DIFFBUS..2
R 2
(-4925 2100);
FORCEPROP 1 LAST LOCATION C578
J 2
(-4725 2100);
DISPLAY 0.723404 (-4725 2100);
PAINT GREEN (-4725 2100);
FORCEPROP 0 LAST $SEC 1
J 0
(-4725 2150);
DISPLAY 0.680851 (-4725 2150);
PAINT MONO (-4725 2150);
DISPLAY INVISIBLE (-4725 2150);
FORCEPROP 0 LAST CDS_SEC 1
J 0
(-4725 2150);
DISPLAY 0.680851 (-4725 2150);
DISPLAY INVISIBLE (-4725 2150);
FORCEPROP 0 LASTPIN (-4850 2100) $PN 1
J 0
(-4840 2110);
DISPLAY 0.680851 (-4840 2110);
PAINT MONO (-4840 2110);
FORCEPROP 0 LASTPIN (-5000 2100) $PN 2
J 2
(-5010 2110);
DISPLAY 0.680851 (-5010 2110);
PAINT MONO (-5010 2110);
FORCEPROP 2 LAST VALUE DIFF BUS_0.22UF
J 2
(-5050 2100);
DISPLAY 0.553191 (-5050 2100);
FORCEPROP 0 LAST PACK_TYPE C0201
J 2
(-5075 2100);
DISPLAY 0.680851 (-5075 2100);
DISPLAY INVISIBLE (-5075 2100);
FORCEPROP 1 LAST PIN_NAMES_ROTATE True
J 2
(-4925 2100);
DISPLAY 0.489362 (-4925 2100);
PAINT GREEN (-4925 2100);
DISPLAY INVISIBLE (-4925 2100);
FORCEPROP 1 LAST MATERIAL X6S
J 2
(-4775 2150);
DISPLAY 0.723404 (-4775 2150);
PAINT GREEN (-4775 2150);
DISPLAY INVISIBLE (-4775 2150);
FORCEPROP 1 LAST PART_NUMBER SP_CH4221MEE01
J 2
(-4900 2175);
DISPLAY 0.723404 (-4900 2175);
PAINT GREEN (-4900 2175);
DISPLAY INVISIBLE (-4900 2175);
FORCEPROP 0 LAST TOLERANCE 20%
J 2
(-5000 2225);
DISPLAY 0.680851 (-5000 2225);
DISPLAY INVISIBLE (-5000 2225);
FORCEPROP 0 LAST VOLTAGE 6.3V
J 2
(-5000 2275);
DISPLAY 0.680851 (-5000 2275);
DISPLAY INVISIBLE (-5000 2275);
FORCEPROP 1 LAST CDS_LMAN_SYM_OUTLINE -25,50,25,-50
J 2
(-4925 2100);
DISPLAY 0.468085 (-4925 2100);
PAINT GREEN (-4925 2100);
DISPLAY INVISIBLE (-4925 2100);
FORCEPROP 1 LAST PATH I159
J 2
(-4925 2100);
DISPLAY 0.723404 (-4925 2100);
DISPLAY INVISIBLE (-4925 2100);
FORCEPROP 2 LAST CDS_LIB pure_quanta
J 0
(-4925 2100);
DISPLAY INVISIBLE (-4925 2100);
FORCEADD TAP..6
(-5650 4700);
FORCEPROP 3 LASTPIN (-5600 4700) SIG_NAME P5E_CPU0_P0_TX_DP<11>
J 0
(-5590 4710);
DISPLAY 0.659574 (-5590 4710);
PAINT MONO (-5590 4710);
DISPLAY INVISIBLE (-5590 4710);
FORCEPROP 1 LASTPIN (-5600 4700) BN 11
J 0
(-5652 4708);
DISPLAY 0.680851 (-5652 4708);
PAINT MONO (-5652 4708);
FORCEPROP 2 LAST CDS_LIB standard
J 0
(-5650 4700);
DISPLAY INVISIBLE (-5650 4700);
FORCEPROP 1 LAST PATH I16
J 0
(-5652 4700);
DISPLAY 0.872340 (-5652 4700);
PAINT GREEN (-5652 4700);
DISPLAY INVISIBLE (-5652 4700);
FORCEPROP 1 LAST BODY_TYPE PLUMBING
J 0
(-5650 4650);
DISPLAY 0.574468 (-5650 4650);
PAINT GREEN (-5650 4650);
DISPLAY INVISIBLE (-5650 4650);
FORCEPROP 1 LAST HDL_TAP TRUE
J 0
(-5325 4575);
DISPLAY 0.574468 (-5325 4575);
PAINT GREEN (-5325 4575);
DISPLAY INVISIBLE (-5325 4575);
FORCEADD Q_CAP_DIFFBUS..2
R 2
(-4925 2050);
FORCEPROP 1 LAST LOCATION C579
J 2
(-4700 2050);
DISPLAY 0.723404 (-4700 2050);
PAINT GREEN (-4700 2050);
FORCEPROP 0 LAST $SEC 1
J 0
(-4700 2100);
DISPLAY 0.680851 (-4700 2100);
PAINT MONO (-4700 2100);
DISPLAY INVISIBLE (-4700 2100);
FORCEPROP 0 LAST CDS_SEC 1
J 0
(-4700 2100);
DISPLAY 0.680851 (-4700 2100);
DISPLAY INVISIBLE (-4700 2100);
FORCEPROP 0 LASTPIN (-4850 2050) $PN 1
J 0
(-4840 2060);
DISPLAY 0.680851 (-4840 2060);
PAINT MONO (-4840 2060);
FORCEPROP 0 LASTPIN (-5000 2050) $PN 2
J 2
(-5010 2060);
DISPLAY 0.680851 (-5010 2060);
PAINT MONO (-5010 2060);
FORCEPROP 2 LAST VALUE DIFF BUS_0.22UF
J 2
(-5050 2050);
DISPLAY 0.553191 (-5050 2050);
FORCEPROP 0 LAST PACK_TYPE C0201
J 2
(-5075 2050);
DISPLAY 0.680851 (-5075 2050);
DISPLAY INVISIBLE (-5075 2050);
FORCEPROP 1 LAST PIN_NAMES_ROTATE True
J 2
(-4925 2050);
DISPLAY 0.489362 (-4925 2050);
PAINT GREEN (-4925 2050);
DISPLAY INVISIBLE (-4925 2050);
FORCEPROP 1 LAST MATERIAL X6S
J 2
(-4775 2100);
DISPLAY 0.723404 (-4775 2100);
PAINT GREEN (-4775 2100);
DISPLAY INVISIBLE (-4775 2100);
FORCEPROP 1 LAST PART_NUMBER SP_CH4221MEE01
J 2
(-4900 2125);
DISPLAY 0.723404 (-4900 2125);
PAINT GREEN (-4900 2125);
DISPLAY INVISIBLE (-4900 2125);
FORCEPROP 0 LAST TOLERANCE 20%
J 2
(-5000 2175);
DISPLAY 0.680851 (-5000 2175);
DISPLAY INVISIBLE (-5000 2175);
FORCEPROP 0 LAST VOLTAGE 6.3V
J 2
(-5000 2225);
DISPLAY 0.680851 (-5000 2225);
DISPLAY INVISIBLE (-5000 2225);
FORCEPROP 1 LAST CDS_LMAN_SYM_OUTLINE -25,50,25,-50
J 2
(-4925 2050);
DISPLAY 0.468085 (-4925 2050);
PAINT GREEN (-4925 2050);
DISPLAY INVISIBLE (-4925 2050);
FORCEPROP 1 LAST PATH I160
J 2
(-4925 2050);
DISPLAY 0.723404 (-4925 2050);
DISPLAY INVISIBLE (-4925 2050);
FORCEPROP 2 LAST CDS_LIB pure_quanta
J 0
(-4925 2050);
DISPLAY INVISIBLE (-4925 2050);
FORCEADD Q_CAP_DIFFBUS..2
R 2
(-4925 2000);
FORCEPROP 1 LAST LOCATION C580
J 2
(-4700 2000);
DISPLAY 0.723404 (-4700 2000);
PAINT GREEN (-4700 2000);
FORCEPROP 0 LAST $SEC 1
J 0
(-4700 2050);
DISPLAY 0.680851 (-4700 2050);
PAINT MONO (-4700 2050);
DISPLAY INVISIBLE (-4700 2050);
FORCEPROP 0 LAST CDS_SEC 1
J 0
(-4700 2050);
DISPLAY 0.680851 (-4700 2050);
DISPLAY INVISIBLE (-4700 2050);
FORCEPROP 0 LASTPIN (-4850 2000) $PN 1
J 0
(-4840 2010);
DISPLAY 0.680851 (-4840 2010);
PAINT MONO (-4840 2010);
FORCEPROP 0 LASTPIN (-5000 2000) $PN 2
J 2
(-5010 2010);
DISPLAY 0.680851 (-5010 2010);
PAINT MONO (-5010 2010);
FORCEPROP 2 LAST VALUE DIFF BUS_0.22UF
J 2
(-5050 2000);
DISPLAY 0.553191 (-5050 2000);
FORCEPROP 0 LAST PACK_TYPE C0201
J 2
(-5075 2000);
DISPLAY 0.680851 (-5075 2000);
DISPLAY INVISIBLE (-5075 2000);
FORCEPROP 1 LAST PIN_NAMES_ROTATE True
J 2
(-4925 2000);
DISPLAY 0.489362 (-4925 2000);
PAINT GREEN (-4925 2000);
DISPLAY INVISIBLE (-4925 2000);
FORCEPROP 1 LAST MATERIAL X6S
J 2
(-4775 2050);
DISPLAY 0.723404 (-4775 2050);
PAINT GREEN (-4775 2050);
DISPLAY INVISIBLE (-4775 2050);
FORCEPROP 1 LAST PART_NUMBER SP_CH4221MEE01
J 2
(-4900 2075);
DISPLAY 0.723404 (-4900 2075);
PAINT GREEN (-4900 2075);
DISPLAY INVISIBLE (-4900 2075);
FORCEPROP 0 LAST TOLERANCE 20%
J 2
(-5000 2125);
DISPLAY 0.680851 (-5000 2125);
DISPLAY INVISIBLE (-5000 2125);
FORCEPROP 0 LAST VOLTAGE 6.3V
J 2
(-5000 2175);
DISPLAY 0.680851 (-5000 2175);
DISPLAY INVISIBLE (-5000 2175);
FORCEPROP 1 LAST CDS_LMAN_SYM_OUTLINE -25,50,25,-50
J 2
(-4925 2000);
DISPLAY 0.468085 (-4925 2000);
PAINT GREEN (-4925 2000);
DISPLAY INVISIBLE (-4925 2000);
FORCEPROP 1 LAST PATH I161
J 2
(-4925 2000);
DISPLAY 0.723404 (-4925 2000);
DISPLAY INVISIBLE (-4925 2000);
FORCEPROP 2 LAST CDS_LIB pure_quanta
J 0
(-4925 2000);
DISPLAY INVISIBLE (-4925 2000);
FORCEADD Q_CAP_DIFFBUS..2
R 2
(-4925 1950);
FORCEPROP 1 LAST LOCATION C581
J 2
(-4700 1950);
DISPLAY 0.723404 (-4700 1950);
PAINT GREEN (-4700 1950);
FORCEPROP 0 LAST $SEC 1
J 0
(-4700 2000);
DISPLAY 0.680851 (-4700 2000);
PAINT MONO (-4700 2000);
DISPLAY INVISIBLE (-4700 2000);
FORCEPROP 0 LAST CDS_SEC 1
J 0
(-4700 2000);
DISPLAY 0.680851 (-4700 2000);
DISPLAY INVISIBLE (-4700 2000);
FORCEPROP 0 LASTPIN (-4850 1950) $PN 1
J 0
(-4840 1960);
DISPLAY 0.680851 (-4840 1960);
PAINT MONO (-4840 1960);
FORCEPROP 0 LASTPIN (-5000 1950) $PN 2
J 2
(-5010 1960);
DISPLAY 0.680851 (-5010 1960);
PAINT MONO (-5010 1960);
FORCEPROP 2 LAST VALUE DIFF BUS_0.22UF
J 2
(-5050 1950);
DISPLAY 0.553191 (-5050 1950);
FORCEPROP 0 LAST PACK_TYPE C0201
J 2
(-5075 1950);
DISPLAY 0.680851 (-5075 1950);
DISPLAY INVISIBLE (-5075 1950);
FORCEPROP 1 LAST PIN_NAMES_ROTATE True
J 2
(-4925 1950);
DISPLAY 0.489362 (-4925 1950);
PAINT GREEN (-4925 1950);
DISPLAY INVISIBLE (-4925 1950);
FORCEPROP 1 LAST MATERIAL X6S
J 2
(-4775 2000);
DISPLAY 0.723404 (-4775 2000);
PAINT GREEN (-4775 2000);
DISPLAY INVISIBLE (-4775 2000);
FORCEPROP 1 LAST PART_NUMBER SP_CH4221MEE01
J 2
(-4900 2025);
DISPLAY 0.723404 (-4900 2025);
PAINT GREEN (-4900 2025);
DISPLAY INVISIBLE (-4900 2025);
FORCEPROP 0 LAST TOLERANCE 20%
J 2
(-5000 2075);
DISPLAY 0.680851 (-5000 2075);
DISPLAY INVISIBLE (-5000 2075);
FORCEPROP 0 LAST VOLTAGE 6.3V
J 2
(-5000 2125);
DISPLAY 0.680851 (-5000 2125);
DISPLAY INVISIBLE (-5000 2125);
FORCEPROP 1 LAST CDS_LMAN_SYM_OUTLINE -25,50,25,-50
J 2
(-4925 1950);
DISPLAY 0.468085 (-4925 1950);
PAINT GREEN (-4925 1950);
DISPLAY INVISIBLE (-4925 1950);
FORCEPROP 1 LAST PATH I162
J 2
(-4925 1950);
DISPLAY 0.723404 (-4925 1950);
DISPLAY INVISIBLE (-4925 1950);
FORCEPROP 2 LAST CDS_LIB pure_quanta
J 0
(-4925 1950);
DISPLAY INVISIBLE (-4925 1950);
FORCEADD Q_CAP_DIFFBUS..2
R 2
(-4925 1900);
FORCEPROP 1 LAST LOCATION C582
J 2
(-4700 1900);
DISPLAY 0.723404 (-4700 1900);
PAINT GREEN (-4700 1900);
FORCEPROP 0 LAST $SEC 1
J 0
(-4700 1950);
DISPLAY 0.680851 (-4700 1950);
PAINT MONO (-4700 1950);
DISPLAY INVISIBLE (-4700 1950);
FORCEPROP 0 LAST CDS_SEC 1
J 0
(-4700 1950);
DISPLAY 0.680851 (-4700 1950);
DISPLAY INVISIBLE (-4700 1950);
FORCEPROP 0 LASTPIN (-4850 1900) $PN 1
J 0
(-4840 1910);
DISPLAY 0.680851 (-4840 1910);
PAINT MONO (-4840 1910);
FORCEPROP 0 LASTPIN (-5000 1900) $PN 2
J 2
(-5010 1910);
DISPLAY 0.680851 (-5010 1910);
PAINT MONO (-5010 1910);
FORCEPROP 2 LAST VALUE DIFF BUS_0.22UF
J 2
(-5050 1900);
DISPLAY 0.553191 (-5050 1900);
FORCEPROP 0 LAST VOLTAGE 6.3V
J 2
(-5000 2075);
DISPLAY 0.680851 (-5000 2075);
DISPLAY INVISIBLE (-5000 2075);
FORCEPROP 0 LAST TOLERANCE 20%
J 2
(-5000 2025);
DISPLAY 0.680851 (-5000 2025);
DISPLAY INVISIBLE (-5000 2025);
FORCEPROP 1 LAST PART_NUMBER SP_CH4221MEE01
J 2
(-4900 1975);
DISPLAY 0.723404 (-4900 1975);
PAINT GREEN (-4900 1975);
DISPLAY INVISIBLE (-4900 1975);
FORCEPROP 1 LAST MATERIAL X6S
J 2
(-4775 1950);
DISPLAY 0.723404 (-4775 1950);
PAINT GREEN (-4775 1950);
DISPLAY INVISIBLE (-4775 1950);
FORCEPROP 1 LAST PIN_NAMES_ROTATE True
J 2
(-4925 1900);
DISPLAY 0.489362 (-4925 1900);
PAINT GREEN (-4925 1900);
DISPLAY INVISIBLE (-4925 1900);
FORCEPROP 0 LAST PACK_TYPE C0201
J 2
(-5075 1900);
DISPLAY 0.680851 (-5075 1900);
DISPLAY INVISIBLE (-5075 1900);
FORCEPROP 1 LAST CDS_LMAN_SYM_OUTLINE -25,50,25,-50
J 2
(-4925 1900);
DISPLAY 0.468085 (-4925 1900);
PAINT GREEN (-4925 1900);
DISPLAY INVISIBLE (-4925 1900);
FORCEPROP 1 LAST PATH I163
J 2
(-4925 1900);
DISPLAY 0.723404 (-4925 1900);
DISPLAY INVISIBLE (-4925 1900);
FORCEPROP 2 LAST CDS_LIB pure_quanta
J 0
(-4925 1900);
DISPLAY INVISIBLE (-4925 1900);
FORCEADD Q_CAP_DIFFBUS..2
R 2
(-4925 1800);
FORCEPROP 1 LAST LOCATION C585
J 2
(-4675 1800);
DISPLAY 0.723404 (-4675 1800);
PAINT GREEN (-4675 1800);
FORCEPROP 0 LAST $SEC 1
J 0
(-4675 1850);
DISPLAY 0.680851 (-4675 1850);
PAINT MONO (-4675 1850);
DISPLAY INVISIBLE (-4675 1850);
FORCEPROP 0 LAST CDS_SEC 1
J 0
(-4675 1850);
DISPLAY 0.680851 (-4675 1850);
DISPLAY INVISIBLE (-4675 1850);
FORCEPROP 0 LASTPIN (-4850 1800) $PN 1
J 0
(-4840 1810);
DISPLAY 0.680851 (-4840 1810);
PAINT MONO (-4840 1810);
FORCEPROP 0 LASTPIN (-5000 1800) $PN 2
J 2
(-5010 1810);
DISPLAY 0.680851 (-5010 1810);
PAINT MONO (-5010 1810);
FORCEPROP 2 LAST VALUE DIFF BUS_0.22UF
J 2
(-5050 1800);
DISPLAY 0.553191 (-5050 1800);
FORCEPROP 0 LAST VOLTAGE 6.3V
J 2
(-5000 1975);
DISPLAY 0.680851 (-5000 1975);
DISPLAY INVISIBLE (-5000 1975);
FORCEPROP 0 LAST TOLERANCE 20%
J 2
(-5000 1925);
DISPLAY 0.680851 (-5000 1925);
DISPLAY INVISIBLE (-5000 1925);
FORCEPROP 1 LAST PART_NUMBER SP_CH4221MEE01
J 2
(-4900 1875);
DISPLAY 0.723404 (-4900 1875);
PAINT GREEN (-4900 1875);
DISPLAY INVISIBLE (-4900 1875);
FORCEPROP 1 LAST MATERIAL X6S
J 2
(-4775 1850);
DISPLAY 0.723404 (-4775 1850);
PAINT GREEN (-4775 1850);
DISPLAY INVISIBLE (-4775 1850);
FORCEPROP 1 LAST PIN_NAMES_ROTATE True
J 2
(-4925 1800);
DISPLAY 0.489362 (-4925 1800);
PAINT GREEN (-4925 1800);
DISPLAY INVISIBLE (-4925 1800);
FORCEPROP 0 LAST PACK_TYPE C0201
J 2
(-5075 1800);
DISPLAY 0.680851 (-5075 1800);
DISPLAY INVISIBLE (-5075 1800);
FORCEPROP 1 LAST CDS_LMAN_SYM_OUTLINE -25,50,25,-50
J 2
(-4925 1800);
DISPLAY 0.468085 (-4925 1800);
PAINT GREEN (-4925 1800);
DISPLAY INVISIBLE (-4925 1800);
FORCEPROP 1 LAST PATH I164
J 2
(-4925 1800);
DISPLAY 0.723404 (-4925 1800);
DISPLAY INVISIBLE (-4925 1800);
FORCEPROP 2 LAST CDS_LIB pure_quanta
J 0
(-4925 1800);
DISPLAY INVISIBLE (-4925 1800);
FORCEADD Q_CAP_DIFFBUS..2
R 2
(-4925 1750);
FORCEPROP 1 LAST LOCATION C586
J 2
(-4700 1750);
DISPLAY 0.723404 (-4700 1750);
PAINT GREEN (-4700 1750);
FORCEPROP 0 LAST $SEC 1
J 0
(-4700 1800);
DISPLAY 0.680851 (-4700 1800);
PAINT MONO (-4700 1800);
DISPLAY INVISIBLE (-4700 1800);
FORCEPROP 0 LAST CDS_SEC 1
J 0
(-4700 1800);
DISPLAY 0.680851 (-4700 1800);
DISPLAY INVISIBLE (-4700 1800);
FORCEPROP 0 LASTPIN (-4850 1750) $PN 1
J 0
(-4840 1760);
DISPLAY 0.680851 (-4840 1760);
PAINT MONO (-4840 1760);
FORCEPROP 0 LASTPIN (-5000 1750) $PN 2
J 2
(-5010 1760);
DISPLAY 0.680851 (-5010 1760);
PAINT MONO (-5010 1760);
FORCEPROP 2 LAST VALUE DIFF BUS_0.22UF
J 2
(-5050 1750);
DISPLAY 0.553191 (-5050 1750);
FORCEPROP 0 LAST VOLTAGE 6.3V
J 2
(-5000 1925);
DISPLAY 0.680851 (-5000 1925);
DISPLAY INVISIBLE (-5000 1925);
FORCEPROP 0 LAST TOLERANCE 20%
J 2
(-5000 1875);
DISPLAY 0.680851 (-5000 1875);
DISPLAY INVISIBLE (-5000 1875);
FORCEPROP 1 LAST PART_NUMBER SP_CH4221MEE01
J 2
(-4900 1825);
DISPLAY 0.723404 (-4900 1825);
PAINT GREEN (-4900 1825);
DISPLAY INVISIBLE (-4900 1825);
FORCEPROP 1 LAST MATERIAL X6S
J 2
(-4775 1800);
DISPLAY 0.723404 (-4775 1800);
PAINT GREEN (-4775 1800);
DISPLAY INVISIBLE (-4775 1800);
FORCEPROP 1 LAST PIN_NAMES_ROTATE True
J 2
(-4925 1750);
DISPLAY 0.489362 (-4925 1750);
PAINT GREEN (-4925 1750);
DISPLAY INVISIBLE (-4925 1750);
FORCEPROP 0 LAST PACK_TYPE C0201
J 2
(-5075 1750);
DISPLAY 0.680851 (-5075 1750);
DISPLAY INVISIBLE (-5075 1750);
FORCEPROP 1 LAST CDS_LMAN_SYM_OUTLINE -25,50,25,-50
J 2
(-4925 1750);
DISPLAY 0.468085 (-4925 1750);
PAINT GREEN (-4925 1750);
DISPLAY INVISIBLE (-4925 1750);
FORCEPROP 1 LAST PATH I165
J 2
(-4925 1750);
DISPLAY 0.723404 (-4925 1750);
DISPLAY INVISIBLE (-4925 1750);
FORCEPROP 2 LAST CDS_LIB pure_quanta
J 0
(-4925 1750);
DISPLAY INVISIBLE (-4925 1750);
FORCEADD Q_CAP_DIFFBUS..2
R 2
(-4925 1850);
FORCEPROP 1 LAST LOCATION C583
J 2
(-4700 1850);
DISPLAY 0.723404 (-4700 1850);
PAINT GREEN (-4700 1850);
FORCEPROP 0 LAST $SEC 1
J 0
(-4700 1900);
DISPLAY 0.680851 (-4700 1900);
PAINT MONO (-4700 1900);
DISPLAY INVISIBLE (-4700 1900);
FORCEPROP 0 LAST CDS_SEC 1
J 0
(-4700 1900);
DISPLAY 0.680851 (-4700 1900);
DISPLAY INVISIBLE (-4700 1900);
FORCEPROP 0 LASTPIN (-4850 1850) $PN 1
J 0
(-4840 1860);
DISPLAY 0.680851 (-4840 1860);
PAINT MONO (-4840 1860);
FORCEPROP 0 LASTPIN (-5000 1850) $PN 2
J 2
(-5010 1860);
DISPLAY 0.680851 (-5010 1860);
PAINT MONO (-5010 1860);
FORCEPROP 2 LAST VALUE DIFF BUS_0.22UF
J 2
(-5050 1850);
DISPLAY 0.553191 (-5050 1850);
FORCEPROP 0 LAST VOLTAGE 6.3V
J 2
(-5000 2025);
DISPLAY 0.680851 (-5000 2025);
DISPLAY INVISIBLE (-5000 2025);
FORCEPROP 0 LAST TOLERANCE 20%
J 2
(-5000 1975);
DISPLAY 0.680851 (-5000 1975);
DISPLAY INVISIBLE (-5000 1975);
FORCEPROP 1 LAST PART_NUMBER SP_CH4221MEE01
J 2
(-4900 1925);
DISPLAY 0.723404 (-4900 1925);
PAINT GREEN (-4900 1925);
DISPLAY INVISIBLE (-4900 1925);
FORCEPROP 1 LAST MATERIAL X6S
J 2
(-4775 1900);
DISPLAY 0.723404 (-4775 1900);
PAINT GREEN (-4775 1900);
DISPLAY INVISIBLE (-4775 1900);
FORCEPROP 1 LAST PIN_NAMES_ROTATE True
J 2
(-4925 1850);
DISPLAY 0.489362 (-4925 1850);
PAINT GREEN (-4925 1850);
DISPLAY INVISIBLE (-4925 1850);
FORCEPROP 0 LAST PACK_TYPE C0201
J 2
(-5075 1850);
DISPLAY 0.680851 (-5075 1850);
DISPLAY INVISIBLE (-5075 1850);
FORCEPROP 1 LAST CDS_LMAN_SYM_OUTLINE -25,50,25,-50
J 2
(-4925 1850);
DISPLAY 0.468085 (-4925 1850);
PAINT GREEN (-4925 1850);
DISPLAY INVISIBLE (-4925 1850);
FORCEPROP 1 LAST PATH I166
J 2
(-4925 1850);
DISPLAY 0.723404 (-4925 1850);
DISPLAY INVISIBLE (-4925 1850);
FORCEPROP 2 LAST CDS_LIB pure_quanta
J 0
(-4925 1850);
DISPLAY INVISIBLE (-4925 1850);
FORCEADD TAP..6
(-5650 3300);
FORCEPROP 3 LASTPIN (-5600 3300) SIG_NAME P5E_CPU0_P1_TX_DP<0>
J 0
(-5590 3310);
DISPLAY 0.659574 (-5590 3310);
PAINT MONO (-5590 3310);
DISPLAY INVISIBLE (-5590 3310);
FORCEPROP 1 LASTPIN (-5600 3300) BN 0
J 0
(-5652 3308);
DISPLAY 0.680851 (-5652 3308);
PAINT MONO (-5652 3308);
FORCEPROP 1 LAST HDL_TAP TRUE
J 0
(-5325 3175);
DISPLAY 0.574468 (-5325 3175);
PAINT GREEN (-5325 3175);
DISPLAY INVISIBLE (-5325 3175);
FORCEPROP 1 LAST BODY_TYPE PLUMBING
J 0
(-5650 3250);
DISPLAY 0.574468 (-5650 3250);
PAINT GREEN (-5650 3250);
DISPLAY INVISIBLE (-5650 3250);
FORCEPROP 1 LAST PATH I167
J 0
(-5652 3300);
DISPLAY 0.872340 (-5652 3300);
PAINT GREEN (-5652 3300);
DISPLAY INVISIBLE (-5652 3300);
FORCEPROP 2 LAST CDS_LIB standard
J 0
(-5650 3300);
DISPLAY INVISIBLE (-5650 3300);
FORCEADD TAP..6
(-5650 3200);
FORCEPROP 3 LASTPIN (-5600 3200) SIG_NAME P5E_CPU0_P1_TX_DP<1>
J 0
(-5590 3210);
DISPLAY 0.659574 (-5590 3210);
PAINT MONO (-5590 3210);
DISPLAY INVISIBLE (-5590 3210);
FORCEPROP 1 LASTPIN (-5600 3200) BN 1
J 0
(-5652 3208);
DISPLAY 0.680851 (-5652 3208);
PAINT MONO (-5652 3208);
FORCEPROP 1 LAST HDL_TAP TRUE
J 0
(-5325 3075);
DISPLAY 0.574468 (-5325 3075);
PAINT GREEN (-5325 3075);
DISPLAY INVISIBLE (-5325 3075);
FORCEPROP 1 LAST BODY_TYPE PLUMBING
J 0
(-5650 3150);
DISPLAY 0.574468 (-5650 3150);
PAINT GREEN (-5650 3150);
DISPLAY INVISIBLE (-5650 3150);
FORCEPROP 1 LAST PATH I168
J 0
(-5652 3200);
DISPLAY 0.872340 (-5652 3200);
PAINT GREEN (-5652 3200);
DISPLAY INVISIBLE (-5652 3200);
FORCEPROP 2 LAST CDS_LIB standard
J 0
(-5650 3200);
DISPLAY INVISIBLE (-5650 3200);
FORCEADD TAP..6
(-5800 3150);
FORCEPROP 3 LASTPIN (-5750 3150) SIG_NAME P5E_CPU0_P1_TX_DN<1>
J 0
(-5740 3160);
DISPLAY 0.659574 (-5740 3160);
PAINT MONO (-5740 3160);
DISPLAY INVISIBLE (-5740 3160);
FORCEPROP 1 LASTPIN (-5750 3150) BN 1
J 0
(-5802 3158);
DISPLAY 0.680851 (-5802 3158);
PAINT MONO (-5802 3158);
FORCEPROP 1 LAST HDL_TAP TRUE
J 0
(-5475 3025);
DISPLAY 0.574468 (-5475 3025);
PAINT GREEN (-5475 3025);
DISPLAY INVISIBLE (-5475 3025);
FORCEPROP 1 LAST BODY_TYPE PLUMBING
J 0
(-5800 3100);
DISPLAY 0.574468 (-5800 3100);
PAINT GREEN (-5800 3100);
DISPLAY INVISIBLE (-5800 3100);
FORCEPROP 1 LAST PATH I169
J 0
(-5802 3150);
DISPLAY 0.872340 (-5802 3150);
PAINT GREEN (-5802 3150);
DISPLAY INVISIBLE (-5802 3150);
FORCEPROP 2 LAST CDS_LIB standard
J 0
(-5800 3150);
DISPLAY INVISIBLE (-5800 3150);
FORCEADD TAP..6
(-5650 4900);
FORCEPROP 3 LASTPIN (-5600 4900) SIG_NAME P5E_CPU0_P0_TX_DP<9>
J 0
(-5590 4910);
DISPLAY 0.659574 (-5590 4910);
PAINT MONO (-5590 4910);
DISPLAY INVISIBLE (-5590 4910);
FORCEPROP 1 LASTPIN (-5600 4900) BN 9
J 0
(-5652 4908);
DISPLAY 0.680851 (-5652 4908);
PAINT MONO (-5652 4908);
FORCEPROP 2 LAST CDS_LIB standard
J 0
(-5650 4900);
DISPLAY INVISIBLE (-5650 4900);
FORCEPROP 1 LAST PATH I17
J 0
(-5652 4900);
DISPLAY 0.872340 (-5652 4900);
PAINT GREEN (-5652 4900);
DISPLAY INVISIBLE (-5652 4900);
FORCEPROP 1 LAST BODY_TYPE PLUMBING
J 0
(-5650 4850);
DISPLAY 0.574468 (-5650 4850);
PAINT GREEN (-5650 4850);
DISPLAY INVISIBLE (-5650 4850);
FORCEPROP 1 LAST HDL_TAP TRUE
J 0
(-5325 4775);
DISPLAY 0.574468 (-5325 4775);
PAINT GREEN (-5325 4775);
DISPLAY INVISIBLE (-5325 4775);
FORCEADD TAP..6
(-5800 3250);
FORCEPROP 3 LASTPIN (-5750 3250) SIG_NAME P5E_CPU0_P1_TX_DN<0>
J 0
(-5740 3260);
DISPLAY 0.659574 (-5740 3260);
PAINT MONO (-5740 3260);
DISPLAY INVISIBLE (-5740 3260);
FORCEPROP 1 LASTPIN (-5750 3250) BN 0
J 0
(-5802 3258);
DISPLAY 0.680851 (-5802 3258);
PAINT MONO (-5802 3258);
FORCEPROP 1 LAST HDL_TAP TRUE
J 0
(-5475 3125);
DISPLAY 0.574468 (-5475 3125);
PAINT GREEN (-5475 3125);
DISPLAY INVISIBLE (-5475 3125);
FORCEPROP 1 LAST BODY_TYPE PLUMBING
J 0
(-5800 3200);
DISPLAY 0.574468 (-5800 3200);
PAINT GREEN (-5800 3200);
DISPLAY INVISIBLE (-5800 3200);
FORCEPROP 1 LAST PATH I170
J 0
(-5802 3250);
DISPLAY 0.872340 (-5802 3250);
PAINT GREEN (-5802 3250);
DISPLAY INVISIBLE (-5802 3250);
FORCEPROP 2 LAST CDS_LIB standard
J 0
(-5800 3250);
DISPLAY INVISIBLE (-5800 3250);
FORCEADD TAP..6
(-5650 3100);
FORCEPROP 3 LASTPIN (-5600 3100) SIG_NAME P5E_CPU0_P1_TX_DP<2>
J 0
(-5590 3110);
DISPLAY 0.659574 (-5590 3110);
PAINT MONO (-5590 3110);
DISPLAY INVISIBLE (-5590 3110);
FORCEPROP 1 LASTPIN (-5600 3100) BN 2
J 0
(-5652 3108);
DISPLAY 0.680851 (-5652 3108);
PAINT MONO (-5652 3108);
FORCEPROP 1 LAST HDL_TAP TRUE
J 0
(-5325 2975);
DISPLAY 0.574468 (-5325 2975);
PAINT GREEN (-5325 2975);
DISPLAY INVISIBLE (-5325 2975);
FORCEPROP 1 LAST BODY_TYPE PLUMBING
J 0
(-5650 3050);
DISPLAY 0.574468 (-5650 3050);
PAINT GREEN (-5650 3050);
DISPLAY INVISIBLE (-5650 3050);
FORCEPROP 1 LAST PATH I171
J 0
(-5652 3100);
DISPLAY 0.872340 (-5652 3100);
PAINT GREEN (-5652 3100);
DISPLAY INVISIBLE (-5652 3100);
FORCEPROP 2 LAST CDS_LIB standard
J 0
(-5650 3100);
DISPLAY INVISIBLE (-5650 3100);
FORCEADD TAP..6
(-5650 2900);
FORCEPROP 3 LASTPIN (-5600 2900) SIG_NAME P5E_CPU0_P1_TX_DP<4>
J 0
(-5590 2910);
DISPLAY 0.659574 (-5590 2910);
PAINT MONO (-5590 2910);
DISPLAY INVISIBLE (-5590 2910);
FORCEPROP 1 LASTPIN (-5600 2900) BN 4
J 0
(-5652 2908);
DISPLAY 0.680851 (-5652 2908);
PAINT MONO (-5652 2908);
FORCEPROP 1 LAST HDL_TAP TRUE
J 0
(-5325 2775);
DISPLAY 0.574468 (-5325 2775);
PAINT GREEN (-5325 2775);
DISPLAY INVISIBLE (-5325 2775);
FORCEPROP 1 LAST BODY_TYPE PLUMBING
J 0
(-5650 2850);
DISPLAY 0.574468 (-5650 2850);
PAINT GREEN (-5650 2850);
DISPLAY INVISIBLE (-5650 2850);
FORCEPROP 1 LAST PATH I172
J 0
(-5652 2900);
DISPLAY 0.872340 (-5652 2900);
PAINT GREEN (-5652 2900);
DISPLAY INVISIBLE (-5652 2900);
FORCEPROP 2 LAST CDS_LIB standard
J 0
(-5650 2900);
DISPLAY INVISIBLE (-5650 2900);
FORCEADD TAP..6
(-5650 3000);
FORCEPROP 3 LASTPIN (-5600 3000) SIG_NAME P5E_CPU0_P1_TX_DP<3>
J 0
(-5590 3010);
DISPLAY 0.659574 (-5590 3010);
PAINT MONO (-5590 3010);
DISPLAY INVISIBLE (-5590 3010);
FORCEPROP 1 LASTPIN (-5600 3000) BN 3
J 0
(-5652 3008);
DISPLAY 0.680851 (-5652 3008);
PAINT MONO (-5652 3008);
FORCEPROP 1 LAST HDL_TAP TRUE
J 0
(-5325 2875);
DISPLAY 0.574468 (-5325 2875);
PAINT GREEN (-5325 2875);
DISPLAY INVISIBLE (-5325 2875);
FORCEPROP 1 LAST BODY_TYPE PLUMBING
J 0
(-5650 2950);
DISPLAY 0.574468 (-5650 2950);
PAINT GREEN (-5650 2950);
DISPLAY INVISIBLE (-5650 2950);
FORCEPROP 1 LAST PATH I173
J 0
(-5652 3000);
DISPLAY 0.872340 (-5652 3000);
PAINT GREEN (-5652 3000);
DISPLAY INVISIBLE (-5652 3000);
FORCEPROP 2 LAST CDS_LIB standard
J 0
(-5650 3000);
DISPLAY INVISIBLE (-5650 3000);
FORCEADD TAP..6
(-5800 3050);
FORCEPROP 3 LASTPIN (-5750 3050) SIG_NAME P5E_CPU0_P1_TX_DN<2>
J 0
(-5740 3060);
DISPLAY 0.659574 (-5740 3060);
PAINT MONO (-5740 3060);
DISPLAY INVISIBLE (-5740 3060);
FORCEPROP 1 LASTPIN (-5750 3050) BN 2
J 0
(-5802 3058);
DISPLAY 0.680851 (-5802 3058);
PAINT MONO (-5802 3058);
FORCEPROP 1 LAST HDL_TAP TRUE
J 0
(-5475 2925);
DISPLAY 0.574468 (-5475 2925);
PAINT GREEN (-5475 2925);
DISPLAY INVISIBLE (-5475 2925);
FORCEPROP 1 LAST BODY_TYPE PLUMBING
J 0
(-5800 3000);
DISPLAY 0.574468 (-5800 3000);
PAINT GREEN (-5800 3000);
DISPLAY INVISIBLE (-5800 3000);
FORCEPROP 1 LAST PATH I174
J 0
(-5802 3050);
DISPLAY 0.872340 (-5802 3050);
PAINT GREEN (-5802 3050);
DISPLAY INVISIBLE (-5802 3050);
FORCEPROP 2 LAST CDS_LIB standard
J 0
(-5800 3050);
DISPLAY INVISIBLE (-5800 3050);
FORCEADD TAP..6
(-5800 2950);
FORCEPROP 3 LASTPIN (-5750 2950) SIG_NAME P5E_CPU0_P1_TX_DN<3>
J 0
(-5740 2960);
DISPLAY 0.659574 (-5740 2960);
PAINT MONO (-5740 2960);
DISPLAY INVISIBLE (-5740 2960);
FORCEPROP 1 LASTPIN (-5750 2950) BN 3
J 0
(-5802 2958);
DISPLAY 0.680851 (-5802 2958);
PAINT MONO (-5802 2958);
FORCEPROP 1 LAST HDL_TAP TRUE
J 0
(-5475 2825);
DISPLAY 0.574468 (-5475 2825);
PAINT GREEN (-5475 2825);
DISPLAY INVISIBLE (-5475 2825);
FORCEPROP 1 LAST BODY_TYPE PLUMBING
J 0
(-5800 2900);
DISPLAY 0.574468 (-5800 2900);
PAINT GREEN (-5800 2900);
DISPLAY INVISIBLE (-5800 2900);
FORCEPROP 1 LAST PATH I175
J 0
(-5802 2950);
DISPLAY 0.872340 (-5802 2950);
PAINT GREEN (-5802 2950);
DISPLAY INVISIBLE (-5802 2950);
FORCEPROP 2 LAST CDS_LIB standard
J 0
(-5800 2950);
DISPLAY INVISIBLE (-5800 2950);
FORCEADD TAP..6
(-5650 2800);
FORCEPROP 3 LASTPIN (-5600 2800) SIG_NAME P5E_CPU0_P1_TX_DP<5>
J 0
(-5590 2810);
DISPLAY 0.659574 (-5590 2810);
PAINT MONO (-5590 2810);
DISPLAY INVISIBLE (-5590 2810);
FORCEPROP 1 LASTPIN (-5600 2800) BN 5
J 0
(-5652 2808);
DISPLAY 0.680851 (-5652 2808);
PAINT MONO (-5652 2808);
FORCEPROP 1 LAST HDL_TAP TRUE
J 0
(-5325 2675);
DISPLAY 0.574468 (-5325 2675);
PAINT GREEN (-5325 2675);
DISPLAY INVISIBLE (-5325 2675);
FORCEPROP 1 LAST BODY_TYPE PLUMBING
J 0
(-5650 2750);
DISPLAY 0.574468 (-5650 2750);
PAINT GREEN (-5650 2750);
DISPLAY INVISIBLE (-5650 2750);
FORCEPROP 1 LAST PATH I176
J 0
(-5652 2800);
DISPLAY 0.872340 (-5652 2800);
PAINT GREEN (-5652 2800);
DISPLAY INVISIBLE (-5652 2800);
FORCEPROP 2 LAST CDS_LIB standard
J 0
(-5650 2800);
DISPLAY INVISIBLE (-5650 2800);
FORCEADD TAP..6
(-5650 2700);
FORCEPROP 3 LASTPIN (-5600 2700) SIG_NAME P5E_CPU0_P1_TX_DP<6>
J 0
(-5590 2710);
DISPLAY 0.659574 (-5590 2710);
PAINT MONO (-5590 2710);
DISPLAY INVISIBLE (-5590 2710);
FORCEPROP 1 LASTPIN (-5600 2700) BN 6
J 0
(-5652 2708);
DISPLAY 0.680851 (-5652 2708);
PAINT MONO (-5652 2708);
FORCEPROP 1 LAST HDL_TAP TRUE
J 0
(-5325 2575);
DISPLAY 0.574468 (-5325 2575);
PAINT GREEN (-5325 2575);
DISPLAY INVISIBLE (-5325 2575);
FORCEPROP 1 LAST BODY_TYPE PLUMBING
J 0
(-5650 2650);
DISPLAY 0.574468 (-5650 2650);
PAINT GREEN (-5650 2650);
DISPLAY INVISIBLE (-5650 2650);
FORCEPROP 1 LAST PATH I177
J 0
(-5652 2700);
DISPLAY 0.872340 (-5652 2700);
PAINT GREEN (-5652 2700);
DISPLAY INVISIBLE (-5652 2700);
FORCEPROP 2 LAST CDS_LIB standard
J 0
(-5650 2700);
DISPLAY INVISIBLE (-5650 2700);
FORCEADD TAP..6
(-5800 2750);
FORCEPROP 3 LASTPIN (-5750 2750) SIG_NAME P5E_CPU0_P1_TX_DN<5>
J 0
(-5740 2760);
DISPLAY 0.659574 (-5740 2760);
PAINT MONO (-5740 2760);
DISPLAY INVISIBLE (-5740 2760);
FORCEPROP 1 LASTPIN (-5750 2750) BN 5
J 0
(-5802 2758);
DISPLAY 0.680851 (-5802 2758);
PAINT MONO (-5802 2758);
FORCEPROP 1 LAST HDL_TAP TRUE
J 0
(-5475 2625);
DISPLAY 0.574468 (-5475 2625);
PAINT GREEN (-5475 2625);
DISPLAY INVISIBLE (-5475 2625);
FORCEPROP 1 LAST BODY_TYPE PLUMBING
J 0
(-5800 2700);
DISPLAY 0.574468 (-5800 2700);
PAINT GREEN (-5800 2700);
DISPLAY INVISIBLE (-5800 2700);
FORCEPROP 1 LAST PATH I178
J 0
(-5802 2750);
DISPLAY 0.872340 (-5802 2750);
PAINT GREEN (-5802 2750);
DISPLAY INVISIBLE (-5802 2750);
FORCEPROP 2 LAST CDS_LIB standard
J 0
(-5800 2750);
DISPLAY INVISIBLE (-5800 2750);
FORCEADD TAP..6
(-5800 2850);
FORCEPROP 3 LASTPIN (-5750 2850) SIG_NAME P5E_CPU0_P1_TX_DN<4>
J 0
(-5740 2860);
DISPLAY 0.659574 (-5740 2860);
PAINT MONO (-5740 2860);
DISPLAY INVISIBLE (-5740 2860);
FORCEPROP 1 LASTPIN (-5750 2850) BN 4
J 0
(-5802 2858);
DISPLAY 0.680851 (-5802 2858);
PAINT MONO (-5802 2858);
FORCEPROP 1 LAST HDL_TAP TRUE
J 0
(-5475 2725);
DISPLAY 0.574468 (-5475 2725);
PAINT GREEN (-5475 2725);
DISPLAY INVISIBLE (-5475 2725);
FORCEPROP 1 LAST BODY_TYPE PLUMBING
J 0
(-5800 2800);
DISPLAY 0.574468 (-5800 2800);
PAINT GREEN (-5800 2800);
DISPLAY INVISIBLE (-5800 2800);
FORCEPROP 1 LAST PATH I179
J 0
(-5802 2850);
DISPLAY 0.872340 (-5802 2850);
PAINT GREEN (-5802 2850);
DISPLAY INVISIBLE (-5802 2850);
FORCEPROP 2 LAST CDS_LIB standard
J 0
(-5800 2850);
DISPLAY INVISIBLE (-5800 2850);
FORCEADD TAP..6
(-5650 4800);
FORCEPROP 3 LASTPIN (-5600 4800) SIG_NAME P5E_CPU0_P0_TX_DP<10>
J 0
(-5590 4810);
DISPLAY 0.659574 (-5590 4810);
PAINT MONO (-5590 4810);
DISPLAY INVISIBLE (-5590 4810);
FORCEPROP 1 LASTPIN (-5600 4800) BN 10
J 0
(-5652 4808);
DISPLAY 0.680851 (-5652 4808);
PAINT MONO (-5652 4808);
FORCEPROP 2 LAST CDS_LIB standard
J 0
(-5650 4800);
DISPLAY INVISIBLE (-5650 4800);
FORCEPROP 1 LAST PATH I18
J 0
(-5652 4800);
DISPLAY 0.872340 (-5652 4800);
PAINT GREEN (-5652 4800);
DISPLAY INVISIBLE (-5652 4800);
FORCEPROP 1 LAST BODY_TYPE PLUMBING
J 0
(-5650 4750);
DISPLAY 0.574468 (-5650 4750);
PAINT GREEN (-5650 4750);
DISPLAY INVISIBLE (-5650 4750);
FORCEPROP 1 LAST HDL_TAP TRUE
J 0
(-5325 4675);
DISPLAY 0.574468 (-5325 4675);
PAINT GREEN (-5325 4675);
DISPLAY INVISIBLE (-5325 4675);
FORCEADD TAP..6
(-5800 2650);
FORCEPROP 3 LASTPIN (-5750 2650) SIG_NAME P5E_CPU0_P1_TX_DN<6>
J 0
(-5740 2660);
DISPLAY 0.659574 (-5740 2660);
PAINT MONO (-5740 2660);
DISPLAY INVISIBLE (-5740 2660);
FORCEPROP 1 LASTPIN (-5750 2650) BN 6
J 0
(-5802 2658);
DISPLAY 0.680851 (-5802 2658);
PAINT MONO (-5802 2658);
FORCEPROP 1 LAST HDL_TAP TRUE
J 0
(-5475 2525);
DISPLAY 0.574468 (-5475 2525);
PAINT GREEN (-5475 2525);
DISPLAY INVISIBLE (-5475 2525);
FORCEPROP 1 LAST BODY_TYPE PLUMBING
J 0
(-5800 2600);
DISPLAY 0.574468 (-5800 2600);
PAINT GREEN (-5800 2600);
DISPLAY INVISIBLE (-5800 2600);
FORCEPROP 1 LAST PATH I180
J 0
(-5802 2650);
DISPLAY 0.872340 (-5802 2650);
PAINT GREEN (-5802 2650);
DISPLAY INVISIBLE (-5802 2650);
FORCEPROP 2 LAST CDS_LIB standard
J 0
(-5800 2650);
DISPLAY INVISIBLE (-5800 2650);
FORCEADD TAP..6
(-5650 2600);
FORCEPROP 3 LASTPIN (-5600 2600) SIG_NAME P5E_CPU0_P1_TX_DP<7>
J 0
(-5590 2610);
DISPLAY 0.659574 (-5590 2610);
PAINT MONO (-5590 2610);
DISPLAY INVISIBLE (-5590 2610);
FORCEPROP 1 LASTPIN (-5600 2600) BN 7
J 0
(-5652 2608);
DISPLAY 0.680851 (-5652 2608);
PAINT MONO (-5652 2608);
FORCEPROP 1 LAST HDL_TAP TRUE
J 0
(-5325 2475);
DISPLAY 0.574468 (-5325 2475);
PAINT GREEN (-5325 2475);
DISPLAY INVISIBLE (-5325 2475);
FORCEPROP 1 LAST BODY_TYPE PLUMBING
J 0
(-5650 2550);
DISPLAY 0.574468 (-5650 2550);
PAINT GREEN (-5650 2550);
DISPLAY INVISIBLE (-5650 2550);
FORCEPROP 1 LAST PATH I181
J 0
(-5652 2600);
DISPLAY 0.872340 (-5652 2600);
PAINT GREEN (-5652 2600);
DISPLAY INVISIBLE (-5652 2600);
FORCEPROP 2 LAST CDS_LIB standard
J 0
(-5650 2600);
DISPLAY INVISIBLE (-5650 2600);
FORCEADD TAP..6
(-5650 2500);
FORCEPROP 3 LASTPIN (-5600 2500) SIG_NAME P5E_CPU0_P1_TX_DP<8>
J 0
(-5590 2510);
DISPLAY 0.659574 (-5590 2510);
PAINT MONO (-5590 2510);
DISPLAY INVISIBLE (-5590 2510);
FORCEPROP 1 LASTPIN (-5600 2500) BN 8
J 0
(-5652 2508);
DISPLAY 0.680851 (-5652 2508);
PAINT MONO (-5652 2508);
FORCEPROP 1 LAST HDL_TAP TRUE
J 0
(-5325 2375);
DISPLAY 0.574468 (-5325 2375);
PAINT GREEN (-5325 2375);
DISPLAY INVISIBLE (-5325 2375);
FORCEPROP 1 LAST BODY_TYPE PLUMBING
J 0
(-5650 2450);
DISPLAY 0.574468 (-5650 2450);
PAINT GREEN (-5650 2450);
DISPLAY INVISIBLE (-5650 2450);
FORCEPROP 1 LAST PATH I182
J 0
(-5652 2500);
DISPLAY 0.872340 (-5652 2500);
PAINT GREEN (-5652 2500);
DISPLAY INVISIBLE (-5652 2500);
FORCEPROP 2 LAST CDS_LIB standard
J 0
(-5650 2500);
DISPLAY INVISIBLE (-5650 2500);
FORCEADD TAP..6
(-5650 2400);
FORCEPROP 3 LASTPIN (-5600 2400) SIG_NAME P5E_CPU0_P1_TX_DP<9>
J 0
(-5590 2410);
DISPLAY 0.659574 (-5590 2410);
PAINT MONO (-5590 2410);
DISPLAY INVISIBLE (-5590 2410);
FORCEPROP 1 LASTPIN (-5600 2400) BN 9
J 0
(-5652 2408);
DISPLAY 0.680851 (-5652 2408);
PAINT MONO (-5652 2408);
FORCEPROP 1 LAST HDL_TAP TRUE
J 0
(-5325 2275);
DISPLAY 0.574468 (-5325 2275);
PAINT GREEN (-5325 2275);
DISPLAY INVISIBLE (-5325 2275);
FORCEPROP 1 LAST BODY_TYPE PLUMBING
J 0
(-5650 2350);
DISPLAY 0.574468 (-5650 2350);
PAINT GREEN (-5650 2350);
DISPLAY INVISIBLE (-5650 2350);
FORCEPROP 1 LAST PATH I183
J 0
(-5652 2400);
DISPLAY 0.872340 (-5652 2400);
PAINT GREEN (-5652 2400);
DISPLAY INVISIBLE (-5652 2400);
FORCEPROP 2 LAST CDS_LIB standard
J 0
(-5650 2400);
DISPLAY INVISIBLE (-5650 2400);
FORCEADD TAP..6
(-5800 2550);
FORCEPROP 3 LASTPIN (-5750 2550) SIG_NAME P5E_CPU0_P1_TX_DN<7>
J 0
(-5740 2560);
DISPLAY 0.659574 (-5740 2560);
PAINT MONO (-5740 2560);
DISPLAY INVISIBLE (-5740 2560);
FORCEPROP 1 LASTPIN (-5750 2550) BN 7
J 0
(-5802 2558);
DISPLAY 0.680851 (-5802 2558);
PAINT MONO (-5802 2558);
FORCEPROP 1 LAST HDL_TAP TRUE
J 0
(-5475 2425);
DISPLAY 0.574468 (-5475 2425);
PAINT GREEN (-5475 2425);
DISPLAY INVISIBLE (-5475 2425);
FORCEPROP 1 LAST BODY_TYPE PLUMBING
J 0
(-5800 2500);
DISPLAY 0.574468 (-5800 2500);
PAINT GREEN (-5800 2500);
DISPLAY INVISIBLE (-5800 2500);
FORCEPROP 1 LAST PATH I184
J 0
(-5802 2550);
DISPLAY 0.872340 (-5802 2550);
PAINT GREEN (-5802 2550);
DISPLAY INVISIBLE (-5802 2550);
FORCEPROP 2 LAST CDS_LIB standard
J 0
(-5800 2550);
DISPLAY INVISIBLE (-5800 2550);
FORCEADD TAP..6
(-5800 2450);
FORCEPROP 3 LASTPIN (-5750 2450) SIG_NAME P5E_CPU0_P1_TX_DN<8>
J 0
(-5740 2460);
DISPLAY 0.659574 (-5740 2460);
PAINT MONO (-5740 2460);
DISPLAY INVISIBLE (-5740 2460);
FORCEPROP 1 LASTPIN (-5750 2450) BN 8
J 0
(-5802 2458);
DISPLAY 0.680851 (-5802 2458);
PAINT MONO (-5802 2458);
FORCEPROP 1 LAST HDL_TAP TRUE
J 0
(-5475 2325);
DISPLAY 0.574468 (-5475 2325);
PAINT GREEN (-5475 2325);
DISPLAY INVISIBLE (-5475 2325);
FORCEPROP 1 LAST BODY_TYPE PLUMBING
J 0
(-5800 2400);
DISPLAY 0.574468 (-5800 2400);
PAINT GREEN (-5800 2400);
DISPLAY INVISIBLE (-5800 2400);
FORCEPROP 1 LAST PATH I185
J 0
(-5802 2450);
DISPLAY 0.872340 (-5802 2450);
PAINT GREEN (-5802 2450);
DISPLAY INVISIBLE (-5802 2450);
FORCEPROP 2 LAST CDS_LIB standard
J 0
(-5800 2450);
DISPLAY INVISIBLE (-5800 2450);
FORCEADD TAP..6
(-5650 2300);
FORCEPROP 3 LASTPIN (-5600 2300) SIG_NAME P5E_CPU0_P1_TX_DP<10>
J 0
(-5590 2310);
DISPLAY 0.659574 (-5590 2310);
PAINT MONO (-5590 2310);
DISPLAY INVISIBLE (-5590 2310);
FORCEPROP 1 LASTPIN (-5600 2300) BN 10
J 0
(-5652 2308);
DISPLAY 0.680851 (-5652 2308);
PAINT MONO (-5652 2308);
FORCEPROP 1 LAST HDL_TAP TRUE
J 0
(-5325 2175);
DISPLAY 0.574468 (-5325 2175);
PAINT GREEN (-5325 2175);
DISPLAY INVISIBLE (-5325 2175);
FORCEPROP 1 LAST BODY_TYPE PLUMBING
J 0
(-5650 2250);
DISPLAY 0.574468 (-5650 2250);
PAINT GREEN (-5650 2250);
DISPLAY INVISIBLE (-5650 2250);
FORCEPROP 1 LAST PATH I186
J 0
(-5652 2300);
DISPLAY 0.872340 (-5652 2300);
PAINT GREEN (-5652 2300);
DISPLAY INVISIBLE (-5652 2300);
FORCEPROP 2 LAST CDS_LIB standard
J 0
(-5650 2300);
DISPLAY INVISIBLE (-5650 2300);
FORCEADD TAP..6
(-5650 2200);
FORCEPROP 3 LASTPIN (-5600 2200) SIG_NAME P5E_CPU0_P1_TX_DP<11>
J 0
(-5590 2210);
DISPLAY 0.659574 (-5590 2210);
PAINT MONO (-5590 2210);
DISPLAY INVISIBLE (-5590 2210);
FORCEPROP 1 LASTPIN (-5600 2200) BN 11
J 0
(-5652 2208);
DISPLAY 0.680851 (-5652 2208);
PAINT MONO (-5652 2208);
FORCEPROP 1 LAST HDL_TAP TRUE
J 0
(-5325 2075);
DISPLAY 0.574468 (-5325 2075);
PAINT GREEN (-5325 2075);
DISPLAY INVISIBLE (-5325 2075);
FORCEPROP 1 LAST BODY_TYPE PLUMBING
J 0
(-5650 2150);
DISPLAY 0.574468 (-5650 2150);
PAINT GREEN (-5650 2150);
DISPLAY INVISIBLE (-5650 2150);
FORCEPROP 1 LAST PATH I187
J 0
(-5652 2200);
DISPLAY 0.872340 (-5652 2200);
PAINT GREEN (-5652 2200);
DISPLAY INVISIBLE (-5652 2200);
FORCEPROP 2 LAST CDS_LIB standard
J 0
(-5650 2200);
DISPLAY INVISIBLE (-5650 2200);
FORCEADD TAP..6
(-5800 2350);
FORCEPROP 3 LASTPIN (-5750 2350) SIG_NAME P5E_CPU0_P1_TX_DN<9>
J 0
(-5740 2360);
DISPLAY 0.659574 (-5740 2360);
PAINT MONO (-5740 2360);
DISPLAY INVISIBLE (-5740 2360);
FORCEPROP 1 LASTPIN (-5750 2350) BN 9
J 0
(-5802 2358);
DISPLAY 0.680851 (-5802 2358);
PAINT MONO (-5802 2358);
FORCEPROP 1 LAST HDL_TAP TRUE
J 0
(-5475 2225);
DISPLAY 0.574468 (-5475 2225);
PAINT GREEN (-5475 2225);
DISPLAY INVISIBLE (-5475 2225);
FORCEPROP 1 LAST BODY_TYPE PLUMBING
J 0
(-5800 2300);
DISPLAY 0.574468 (-5800 2300);
PAINT GREEN (-5800 2300);
DISPLAY INVISIBLE (-5800 2300);
FORCEPROP 1 LAST PATH I188
J 0
(-5802 2350);
DISPLAY 0.872340 (-5802 2350);
PAINT GREEN (-5802 2350);
DISPLAY INVISIBLE (-5802 2350);
FORCEPROP 2 LAST CDS_LIB standard
J 0
(-5800 2350);
DISPLAY INVISIBLE (-5800 2350);
FORCEADD TAP..6
(-5800 2250);
FORCEPROP 3 LASTPIN (-5750 2250) SIG_NAME P5E_CPU0_P1_TX_DN<10>
J 0
(-5740 2260);
DISPLAY 0.659574 (-5740 2260);
PAINT MONO (-5740 2260);
DISPLAY INVISIBLE (-5740 2260);
FORCEPROP 1 LASTPIN (-5750 2250) BN 10
J 0
(-5802 2258);
DISPLAY 0.680851 (-5802 2258);
PAINT MONO (-5802 2258);
FORCEPROP 1 LAST HDL_TAP TRUE
J 0
(-5475 2125);
DISPLAY 0.574468 (-5475 2125);
PAINT GREEN (-5475 2125);
DISPLAY INVISIBLE (-5475 2125);
FORCEPROP 1 LAST BODY_TYPE PLUMBING
J 0
(-5800 2200);
DISPLAY 0.574468 (-5800 2200);
PAINT GREEN (-5800 2200);
DISPLAY INVISIBLE (-5800 2200);
FORCEPROP 1 LAST PATH I189
J 0
(-5802 2250);
DISPLAY 0.872340 (-5802 2250);
PAINT GREEN (-5802 2250);
DISPLAY INVISIBLE (-5802 2250);
FORCEPROP 2 LAST CDS_LIB standard
J 0
(-5800 2250);
DISPLAY INVISIBLE (-5800 2250);
FORCEADD TAP..6
(-5800 5350);
FORCEPROP 3 LASTPIN (-5750 5350) SIG_NAME P5E_CPU0_P0_TX_DN<4>
J 0
(-5740 5360);
DISPLAY 0.659574 (-5740 5360);
PAINT MONO (-5740 5360);
DISPLAY INVISIBLE (-5740 5360);
FORCEPROP 1 LASTPIN (-5750 5350) BN 4
J 0
(-5802 5358);
DISPLAY 0.680851 (-5802 5358);
PAINT MONO (-5802 5358);
FORCEPROP 2 LAST CDS_LIB standard
J 0
(-5800 5350);
DISPLAY INVISIBLE (-5800 5350);
FORCEPROP 1 LAST PATH I19
J 0
(-5802 5350);
DISPLAY 0.872340 (-5802 5350);
PAINT GREEN (-5802 5350);
DISPLAY INVISIBLE (-5802 5350);
FORCEPROP 1 LAST BODY_TYPE PLUMBING
J 0
(-5800 5300);
DISPLAY 0.574468 (-5800 5300);
PAINT GREEN (-5800 5300);
DISPLAY INVISIBLE (-5800 5300);
FORCEPROP 1 LAST HDL_TAP TRUE
J 0
(-5475 5225);
DISPLAY 0.574468 (-5475 5225);
PAINT GREEN (-5475 5225);
DISPLAY INVISIBLE (-5475 5225);
FORCEADD TAP..6
(-5800 2150);
FORCEPROP 3 LASTPIN (-5750 2150) SIG_NAME P5E_CPU0_P1_TX_DN<11>
J 0
(-5740 2160);
DISPLAY 0.659574 (-5740 2160);
PAINT MONO (-5740 2160);
DISPLAY INVISIBLE (-5740 2160);
FORCEPROP 1 LASTPIN (-5750 2150) BN 11
J 0
(-5802 2158);
DISPLAY 0.680851 (-5802 2158);
PAINT MONO (-5802 2158);
FORCEPROP 1 LAST HDL_TAP TRUE
J 0
(-5475 2025);
DISPLAY 0.574468 (-5475 2025);
PAINT GREEN (-5475 2025);
DISPLAY INVISIBLE (-5475 2025);
FORCEPROP 1 LAST BODY_TYPE PLUMBING
J 0
(-5800 2100);
DISPLAY 0.574468 (-5800 2100);
PAINT GREEN (-5800 2100);
DISPLAY INVISIBLE (-5800 2100);
FORCEPROP 1 LAST PATH I190
J 0
(-5802 2150);
DISPLAY 0.872340 (-5802 2150);
PAINT GREEN (-5802 2150);
DISPLAY INVISIBLE (-5802 2150);
FORCEPROP 2 LAST CDS_LIB standard
J 0
(-5800 2150);
DISPLAY INVISIBLE (-5800 2150);
FORCEADD TAP..6
(-5650 2000);
FORCEPROP 3 LASTPIN (-5600 2000) SIG_NAME P5E_CPU0_P1_TX_DP<13>
J 0
(-5590 2010);
DISPLAY 0.659574 (-5590 2010);
PAINT MONO (-5590 2010);
DISPLAY INVISIBLE (-5590 2010);
FORCEPROP 1 LASTPIN (-5600 2000) BN 13
J 0
(-5652 2008);
DISPLAY 0.680851 (-5652 2008);
PAINT MONO (-5652 2008);
FORCEPROP 1 LAST HDL_TAP TRUE
J 0
(-5325 1875);
DISPLAY 0.574468 (-5325 1875);
PAINT GREEN (-5325 1875);
DISPLAY INVISIBLE (-5325 1875);
FORCEPROP 1 LAST BODY_TYPE PLUMBING
J 0
(-5650 1950);
DISPLAY 0.574468 (-5650 1950);
PAINT GREEN (-5650 1950);
DISPLAY INVISIBLE (-5650 1950);
FORCEPROP 1 LAST PATH I191
J 0
(-5652 2000);
DISPLAY 0.872340 (-5652 2000);
PAINT GREEN (-5652 2000);
DISPLAY INVISIBLE (-5652 2000);
FORCEPROP 2 LAST CDS_LIB standard
J 0
(-5650 2000);
DISPLAY INVISIBLE (-5650 2000);
FORCEADD TAP..6
(-5650 2100);
FORCEPROP 3 LASTPIN (-5600 2100) SIG_NAME P5E_CPU0_P1_TX_DP<12>
J 0
(-5590 2110);
DISPLAY 0.659574 (-5590 2110);
PAINT MONO (-5590 2110);
DISPLAY INVISIBLE (-5590 2110);
FORCEPROP 1 LASTPIN (-5600 2100) BN 12
J 0
(-5652 2108);
DISPLAY 0.680851 (-5652 2108);
PAINT MONO (-5652 2108);
FORCEPROP 1 LAST HDL_TAP TRUE
J 0
(-5325 1975);
DISPLAY 0.574468 (-5325 1975);
PAINT GREEN (-5325 1975);
DISPLAY INVISIBLE (-5325 1975);
FORCEPROP 1 LAST BODY_TYPE PLUMBING
J 0
(-5650 2050);
DISPLAY 0.574468 (-5650 2050);
PAINT GREEN (-5650 2050);
DISPLAY INVISIBLE (-5650 2050);
FORCEPROP 1 LAST PATH I192
J 0
(-5652 2100);
DISPLAY 0.872340 (-5652 2100);
PAINT GREEN (-5652 2100);
DISPLAY INVISIBLE (-5652 2100);
FORCEPROP 2 LAST CDS_LIB standard
J 0
(-5650 2100);
DISPLAY INVISIBLE (-5650 2100);
FORCEADD TAP..6
(-5650 1900);
FORCEPROP 3 LASTPIN (-5600 1900) SIG_NAME P5E_CPU0_P1_TX_DP<14>
J 0
(-5590 1910);
DISPLAY 0.659574 (-5590 1910);
PAINT MONO (-5590 1910);
DISPLAY INVISIBLE (-5590 1910);
FORCEPROP 1 LASTPIN (-5600 1900) BN 14
J 0
(-5652 1908);
DISPLAY 0.680851 (-5652 1908);
PAINT MONO (-5652 1908);
FORCEPROP 1 LAST HDL_TAP TRUE
J 0
(-5325 1775);
DISPLAY 0.574468 (-5325 1775);
PAINT GREEN (-5325 1775);
DISPLAY INVISIBLE (-5325 1775);
FORCEPROP 1 LAST BODY_TYPE PLUMBING
J 0
(-5650 1850);
DISPLAY 0.574468 (-5650 1850);
PAINT GREEN (-5650 1850);
DISPLAY INVISIBLE (-5650 1850);
FORCEPROP 1 LAST PATH I193
J 0
(-5652 1900);
DISPLAY 0.872340 (-5652 1900);
PAINT GREEN (-5652 1900);
DISPLAY INVISIBLE (-5652 1900);
FORCEPROP 2 LAST CDS_LIB standard
J 0
(-5650 1900);
DISPLAY INVISIBLE (-5650 1900);
FORCEADD TAP..6
(-5800 2050);
FORCEPROP 3 LASTPIN (-5750 2050) SIG_NAME P5E_CPU0_P1_TX_DN<12>
J 0
(-5740 2060);
DISPLAY 0.659574 (-5740 2060);
PAINT MONO (-5740 2060);
DISPLAY INVISIBLE (-5740 2060);
FORCEPROP 1 LASTPIN (-5750 2050) BN 12
J 0
(-5802 2058);
DISPLAY 0.680851 (-5802 2058);
PAINT MONO (-5802 2058);
FORCEPROP 1 LAST HDL_TAP TRUE
J 0
(-5475 1925);
DISPLAY 0.574468 (-5475 1925);
PAINT GREEN (-5475 1925);
DISPLAY INVISIBLE (-5475 1925);
FORCEPROP 1 LAST BODY_TYPE PLUMBING
J 0
(-5800 2000);
DISPLAY 0.574468 (-5800 2000);
PAINT GREEN (-5800 2000);
DISPLAY INVISIBLE (-5800 2000);
FORCEPROP 1 LAST PATH I194
J 0
(-5802 2050);
DISPLAY 0.872340 (-5802 2050);
PAINT GREEN (-5802 2050);
DISPLAY INVISIBLE (-5802 2050);
FORCEPROP 2 LAST CDS_LIB standard
J 0
(-5800 2050);
DISPLAY INVISIBLE (-5800 2050);
FORCEADD TAP..6
(-5800 1950);
FORCEPROP 3 LASTPIN (-5750 1950) SIG_NAME P5E_CPU0_P1_TX_DN<13>
J 0
(-5740 1960);
DISPLAY 0.659574 (-5740 1960);
PAINT MONO (-5740 1960);
DISPLAY INVISIBLE (-5740 1960);
FORCEPROP 1 LASTPIN (-5750 1950) BN 13
J 0
(-5802 1958);
DISPLAY 0.680851 (-5802 1958);
PAINT MONO (-5802 1958);
FORCEPROP 1 LAST HDL_TAP TRUE
J 0
(-5475 1825);
DISPLAY 0.574468 (-5475 1825);
PAINT GREEN (-5475 1825);
DISPLAY INVISIBLE (-5475 1825);
FORCEPROP 1 LAST BODY_TYPE PLUMBING
J 0
(-5800 1900);
DISPLAY 0.574468 (-5800 1900);
PAINT GREEN (-5800 1900);
DISPLAY INVISIBLE (-5800 1900);
FORCEPROP 1 LAST PATH I195
J 0
(-5802 1950);
DISPLAY 0.872340 (-5802 1950);
PAINT GREEN (-5802 1950);
DISPLAY INVISIBLE (-5802 1950);
FORCEPROP 2 LAST CDS_LIB standard
J 0
(-5800 1950);
DISPLAY INVISIBLE (-5800 1950);
FORCEADD TAP..6
(-5650 1800);
FORCEPROP 3 LASTPIN (-5600 1800) SIG_NAME P5E_CPU0_P1_TX_DP<15>
J 0
(-5590 1810);
DISPLAY 0.659574 (-5590 1810);
PAINT MONO (-5590 1810);
DISPLAY INVISIBLE (-5590 1810);
FORCEPROP 1 LASTPIN (-5600 1800) BN 15
J 0
(-5652 1808);
DISPLAY 0.680851 (-5652 1808);
PAINT MONO (-5652 1808);
FORCEPROP 1 LAST HDL_TAP TRUE
J 0
(-5325 1675);
DISPLAY 0.574468 (-5325 1675);
PAINT GREEN (-5325 1675);
DISPLAY INVISIBLE (-5325 1675);
FORCEPROP 1 LAST BODY_TYPE PLUMBING
J 0
(-5650 1750);
DISPLAY 0.574468 (-5650 1750);
PAINT GREEN (-5650 1750);
DISPLAY INVISIBLE (-5650 1750);
FORCEPROP 1 LAST PATH I196
J 0
(-5652 1800);
DISPLAY 0.872340 (-5652 1800);
PAINT GREEN (-5652 1800);
DISPLAY INVISIBLE (-5652 1800);
FORCEPROP 2 LAST CDS_LIB standard
J 0
(-5650 1800);
DISPLAY INVISIBLE (-5650 1800);
FORCEADD TAP..6
(-5800 1850);
FORCEPROP 3 LASTPIN (-5750 1850) SIG_NAME P5E_CPU0_P1_TX_DN<14>
J 0
(-5740 1860);
DISPLAY 0.659574 (-5740 1860);
PAINT MONO (-5740 1860);
DISPLAY INVISIBLE (-5740 1860);
FORCEPROP 1 LASTPIN (-5750 1850) BN 14
J 0
(-5802 1858);
DISPLAY 0.680851 (-5802 1858);
PAINT MONO (-5802 1858);
FORCEPROP 1 LAST HDL_TAP TRUE
J 0
(-5475 1725);
DISPLAY 0.574468 (-5475 1725);
PAINT GREEN (-5475 1725);
DISPLAY INVISIBLE (-5475 1725);
FORCEPROP 1 LAST BODY_TYPE PLUMBING
J 0
(-5800 1800);
DISPLAY 0.574468 (-5800 1800);
PAINT GREEN (-5800 1800);
DISPLAY INVISIBLE (-5800 1800);
FORCEPROP 1 LAST PATH I197
J 0
(-5802 1850);
DISPLAY 0.872340 (-5802 1850);
PAINT GREEN (-5802 1850);
DISPLAY INVISIBLE (-5802 1850);
FORCEPROP 2 LAST CDS_LIB standard
J 0
(-5800 1850);
DISPLAY INVISIBLE (-5800 1850);
FORCEADD TAP..6
(-5800 1750);
FORCEPROP 3 LASTPIN (-5750 1750) SIG_NAME P5E_CPU0_P1_TX_DN<15>
J 0
(-5740 1760);
DISPLAY 0.659574 (-5740 1760);
PAINT MONO (-5740 1760);
DISPLAY INVISIBLE (-5740 1760);
FORCEPROP 1 LASTPIN (-5750 1750) BN 15
J 0
(-5802 1758);
DISPLAY 0.680851 (-5802 1758);
PAINT MONO (-5802 1758);
FORCEPROP 1 LAST HDL_TAP TRUE
J 0
(-5475 1625);
DISPLAY 0.574468 (-5475 1625);
PAINT GREEN (-5475 1625);
DISPLAY INVISIBLE (-5475 1625);
FORCEPROP 1 LAST BODY_TYPE PLUMBING
J 0
(-5800 1700);
DISPLAY 0.574468 (-5800 1700);
PAINT GREEN (-5800 1700);
DISPLAY INVISIBLE (-5800 1700);
FORCEPROP 1 LAST PATH I198
J 0
(-5802 1750);
DISPLAY 0.872340 (-5802 1750);
PAINT GREEN (-5802 1750);
DISPLAY INVISIBLE (-5802 1750);
FORCEPROP 2 LAST CDS_LIB standard
J 0
(-5800 1750);
DISPLAY INVISIBLE (-5800 1750);
FORCEADD OFFPAGE..1
(-6750 3525);
FORCEPROP 1 LAST COMMENT_BODY TRUE
J 0
(-6625 3425);
DISPLAY 0.872340 (-6625 3425);
PAINT GREEN (-6625 3425);
DISPLAY INVISIBLE (-6625 3425);
FORCEPROP 1 LAST OFFPAGE TRUE
J 0
(-6425 3400);
DISPLAY 0.872340 (-6425 3400);
PAINT GREEN (-6425 3400);
DISPLAY INVISIBLE (-6425 3400);
FORCEPROP 2 LAST PATH I199
J 0
(-6700 3600);
DISPLAY 0.680851 (-6700 3600);
DISPLAY INVISIBLE (-6700 3600);
FORCEPROP 2 LAST CDS_LIB standard
J 0
(-6750 3525);
DISPLAY INVISIBLE (-6750 3525);
FORCEADD TAP..6
(-5800 4250);
FORCEPROP 3 LASTPIN (-5750 4250) SIG_NAME P5E_CPU0_P0_TX_DN<15>
J 0
(-5740 4260);
DISPLAY 0.659574 (-5740 4260);
PAINT MONO (-5740 4260);
DISPLAY INVISIBLE (-5740 4260);
FORCEPROP 1 LASTPIN (-5750 4250) BN 15
J 0
(-5802 4258);
DISPLAY 0.680851 (-5802 4258);
PAINT MONO (-5802 4258);
FORCEPROP 2 LAST CDS_LIB standard
J 0
(-5800 4250);
DISPLAY INVISIBLE (-5800 4250);
FORCEPROP 1 LAST PATH I2
J 0
(-5802 4250);
DISPLAY 0.872340 (-5802 4250);
PAINT GREEN (-5802 4250);
DISPLAY INVISIBLE (-5802 4250);
FORCEPROP 1 LAST BODY_TYPE PLUMBING
J 0
(-5800 4200);
DISPLAY 0.574468 (-5800 4200);
PAINT GREEN (-5800 4200);
DISPLAY INVISIBLE (-5800 4200);
FORCEPROP 1 LAST HDL_TAP TRUE
J 0
(-5475 4125);
DISPLAY 0.574468 (-5475 4125);
PAINT GREEN (-5475 4125);
DISPLAY INVISIBLE (-5475 4125);
FORCEADD TAP..6
(-5800 5450);
FORCEPROP 3 LASTPIN (-5750 5450) SIG_NAME P5E_CPU0_P0_TX_DN<3>
J 0
(-5740 5460);
DISPLAY 0.659574 (-5740 5460);
PAINT MONO (-5740 5460);
DISPLAY INVISIBLE (-5740 5460);
FORCEPROP 1 LASTPIN (-5750 5450) BN 3
J 0
(-5802 5458);
DISPLAY 0.680851 (-5802 5458);
PAINT MONO (-5802 5458);
FORCEPROP 2 LAST CDS_LIB standard
J 0
(-5800 5450);
DISPLAY INVISIBLE (-5800 5450);
FORCEPROP 1 LAST PATH I20
J 0
(-5802 5450);
DISPLAY 0.872340 (-5802 5450);
PAINT GREEN (-5802 5450);
DISPLAY INVISIBLE (-5802 5450);
FORCEPROP 1 LAST BODY_TYPE PLUMBING
J 0
(-5800 5400);
DISPLAY 0.574468 (-5800 5400);
PAINT GREEN (-5800 5400);
DISPLAY INVISIBLE (-5800 5400);
FORCEPROP 1 LAST HDL_TAP TRUE
J 0
(-5475 5325);
DISPLAY 0.574468 (-5475 5325);
PAINT GREEN (-5475 5325);
DISPLAY INVISIBLE (-5475 5325);
FORCEADD OFFPAGE..1
(-6750 3475);
FORCEPROP 1 LAST COMMENT_BODY TRUE
J 0
(-6625 3375);
DISPLAY 0.872340 (-6625 3375);
PAINT GREEN (-6625 3375);
DISPLAY INVISIBLE (-6625 3375);
FORCEPROP 1 LAST OFFPAGE TRUE
J 0
(-6425 3350);
DISPLAY 0.872340 (-6425 3350);
PAINT GREEN (-6425 3350);
DISPLAY INVISIBLE (-6425 3350);
FORCEPROP 2 LAST PATH I200
J 0
(-6700 3550);
DISPLAY 0.680851 (-6700 3550);
DISPLAY INVISIBLE (-6700 3550);
FORCEPROP 2 LAST CDS_LIB standard
J 0
(-6750 3475);
DISPLAY INVISIBLE (-6750 3475);
FORCEADD TAP..6
(-5800 5550);
FORCEPROP 3 LASTPIN (-5750 5550) SIG_NAME P5E_CPU0_P0_TX_DN<2>
J 0
(-5740 5560);
DISPLAY 0.659574 (-5740 5560);
PAINT MONO (-5740 5560);
DISPLAY INVISIBLE (-5740 5560);
FORCEPROP 1 LASTPIN (-5750 5550) BN 2
J 0
(-5802 5558);
DISPLAY 0.680851 (-5802 5558);
PAINT MONO (-5802 5558);
FORCEPROP 2 LAST CDS_LIB standard
J 0
(-5800 5550);
DISPLAY INVISIBLE (-5800 5550);
FORCEPROP 1 LAST PATH I21
J 0
(-5802 5550);
DISPLAY 0.872340 (-5802 5550);
PAINT GREEN (-5802 5550);
DISPLAY INVISIBLE (-5802 5550);
FORCEPROP 1 LAST BODY_TYPE PLUMBING
J 0
(-5800 5500);
DISPLAY 0.574468 (-5800 5500);
PAINT GREEN (-5800 5500);
DISPLAY INVISIBLE (-5800 5500);
FORCEPROP 1 LAST HDL_TAP TRUE
J 0
(-5475 5425);
DISPLAY 0.574468 (-5475 5425);
PAINT GREEN (-5475 5425);
DISPLAY INVISIBLE (-5475 5425);
FORCEADD TAP..6
(-5800 5650);
FORCEPROP 3 LASTPIN (-5750 5650) SIG_NAME P5E_CPU0_P0_TX_DN<1>
J 0
(-5740 5660);
DISPLAY 0.659574 (-5740 5660);
PAINT MONO (-5740 5660);
DISPLAY INVISIBLE (-5740 5660);
FORCEPROP 1 LASTPIN (-5750 5650) BN 1
J 0
(-5802 5658);
DISPLAY 0.680851 (-5802 5658);
PAINT MONO (-5802 5658);
FORCEPROP 2 LAST CDS_LIB standard
J 0
(-5800 5650);
DISPLAY INVISIBLE (-5800 5650);
FORCEPROP 1 LAST PATH I22
J 0
(-5802 5650);
DISPLAY 0.872340 (-5802 5650);
PAINT GREEN (-5802 5650);
DISPLAY INVISIBLE (-5802 5650);
FORCEPROP 1 LAST BODY_TYPE PLUMBING
J 0
(-5800 5600);
DISPLAY 0.574468 (-5800 5600);
PAINT GREEN (-5800 5600);
DISPLAY INVISIBLE (-5800 5600);
FORCEPROP 1 LAST HDL_TAP TRUE
J 0
(-5475 5525);
DISPLAY 0.574468 (-5475 5525);
PAINT GREEN (-5475 5525);
DISPLAY INVISIBLE (-5475 5525);
FORCEADD TAP..6
(-5650 5200);
FORCEPROP 3 LASTPIN (-5600 5200) SIG_NAME P5E_CPU0_P0_TX_DP<6>
J 0
(-5590 5210);
DISPLAY 0.659574 (-5590 5210);
PAINT MONO (-5590 5210);
DISPLAY INVISIBLE (-5590 5210);
FORCEPROP 1 LASTPIN (-5600 5200) BN 6
J 0
(-5652 5208);
DISPLAY 0.680851 (-5652 5208);
PAINT MONO (-5652 5208);
FORCEPROP 2 LAST CDS_LIB standard
J 0
(-5650 5200);
DISPLAY INVISIBLE (-5650 5200);
FORCEPROP 1 LAST PATH I23
J 0
(-5652 5200);
DISPLAY 0.872340 (-5652 5200);
PAINT GREEN (-5652 5200);
DISPLAY INVISIBLE (-5652 5200);
FORCEPROP 1 LAST BODY_TYPE PLUMBING
J 0
(-5650 5150);
DISPLAY 0.574468 (-5650 5150);
PAINT GREEN (-5650 5150);
DISPLAY INVISIBLE (-5650 5150);
FORCEPROP 1 LAST HDL_TAP TRUE
J 0
(-5325 5075);
DISPLAY 0.574468 (-5325 5075);
PAINT GREEN (-5325 5075);
DISPLAY INVISIBLE (-5325 5075);
FORCEADD TAP..6
(-5650 5300);
FORCEPROP 3 LASTPIN (-5600 5300) SIG_NAME P5E_CPU0_P0_TX_DP<5>
J 0
(-5590 5310);
DISPLAY 0.659574 (-5590 5310);
PAINT MONO (-5590 5310);
DISPLAY INVISIBLE (-5590 5310);
FORCEPROP 1 LASTPIN (-5600 5300) BN 5
J 0
(-5652 5308);
DISPLAY 0.680851 (-5652 5308);
PAINT MONO (-5652 5308);
FORCEPROP 2 LAST CDS_LIB standard
J 0
(-5650 5300);
DISPLAY INVISIBLE (-5650 5300);
FORCEPROP 1 LAST PATH I24
J 0
(-5652 5300);
DISPLAY 0.872340 (-5652 5300);
PAINT GREEN (-5652 5300);
DISPLAY INVISIBLE (-5652 5300);
FORCEPROP 1 LAST BODY_TYPE PLUMBING
J 0
(-5650 5250);
DISPLAY 0.574468 (-5650 5250);
PAINT GREEN (-5650 5250);
DISPLAY INVISIBLE (-5650 5250);
FORCEPROP 1 LAST HDL_TAP TRUE
J 0
(-5325 5175);
DISPLAY 0.574468 (-5325 5175);
PAINT GREEN (-5325 5175);
DISPLAY INVISIBLE (-5325 5175);
FORCEADD TAP..6
(-5650 5400);
FORCEPROP 3 LASTPIN (-5600 5400) SIG_NAME P5E_CPU0_P0_TX_DP<4>
J 0
(-5590 5410);
DISPLAY 0.659574 (-5590 5410);
PAINT MONO (-5590 5410);
DISPLAY INVISIBLE (-5590 5410);
FORCEPROP 1 LASTPIN (-5600 5400) BN 4
J 0
(-5652 5408);
DISPLAY 0.680851 (-5652 5408);
PAINT MONO (-5652 5408);
FORCEPROP 2 LAST CDS_LIB standard
J 0
(-5650 5400);
DISPLAY INVISIBLE (-5650 5400);
FORCEPROP 1 LAST PATH I25
J 0
(-5652 5400);
DISPLAY 0.872340 (-5652 5400);
PAINT GREEN (-5652 5400);
DISPLAY INVISIBLE (-5652 5400);
FORCEPROP 1 LAST BODY_TYPE PLUMBING
J 0
(-5650 5350);
DISPLAY 0.574468 (-5650 5350);
PAINT GREEN (-5650 5350);
DISPLAY INVISIBLE (-5650 5350);
FORCEPROP 1 LAST HDL_TAP TRUE
J 0
(-5325 5275);
DISPLAY 0.574468 (-5325 5275);
PAINT GREEN (-5325 5275);
DISPLAY INVISIBLE (-5325 5275);
FORCEADD TAP..6
(-5650 5500);
FORCEPROP 3 LASTPIN (-5600 5500) SIG_NAME P5E_CPU0_P0_TX_DP<3>
J 0
(-5590 5510);
DISPLAY 0.659574 (-5590 5510);
PAINT MONO (-5590 5510);
DISPLAY INVISIBLE (-5590 5510);
FORCEPROP 1 LASTPIN (-5600 5500) BN 3
J 0
(-5652 5508);
DISPLAY 0.680851 (-5652 5508);
PAINT MONO (-5652 5508);
FORCEPROP 2 LAST CDS_LIB standard
J 0
(-5650 5500);
DISPLAY INVISIBLE (-5650 5500);
FORCEPROP 1 LAST PATH I26
J 0
(-5652 5500);
DISPLAY 0.872340 (-5652 5500);
PAINT GREEN (-5652 5500);
DISPLAY INVISIBLE (-5652 5500);
FORCEPROP 1 LAST BODY_TYPE PLUMBING
J 0
(-5650 5450);
DISPLAY 0.574468 (-5650 5450);
PAINT GREEN (-5650 5450);
DISPLAY INVISIBLE (-5650 5450);
FORCEPROP 1 LAST HDL_TAP TRUE
J 0
(-5325 5375);
DISPLAY 0.574468 (-5325 5375);
PAINT GREEN (-5325 5375);
DISPLAY INVISIBLE (-5325 5375);
FORCEADD TAP..6
(-5650 5600);
FORCEPROP 3 LASTPIN (-5600 5600) SIG_NAME P5E_CPU0_P0_TX_DP<2>
J 0
(-5590 5610);
DISPLAY 0.659574 (-5590 5610);
PAINT MONO (-5590 5610);
DISPLAY INVISIBLE (-5590 5610);
FORCEPROP 1 LASTPIN (-5600 5600) BN 2
J 0
(-5652 5608);
DISPLAY 0.680851 (-5652 5608);
PAINT MONO (-5652 5608);
FORCEPROP 2 LAST CDS_LIB standard
J 0
(-5650 5600);
DISPLAY INVISIBLE (-5650 5600);
FORCEPROP 1 LAST PATH I27
J 0
(-5652 5600);
DISPLAY 0.872340 (-5652 5600);
PAINT GREEN (-5652 5600);
DISPLAY INVISIBLE (-5652 5600);
FORCEPROP 1 LAST BODY_TYPE PLUMBING
J 0
(-5650 5550);
DISPLAY 0.574468 (-5650 5550);
PAINT GREEN (-5650 5550);
DISPLAY INVISIBLE (-5650 5550);
FORCEPROP 1 LAST HDL_TAP TRUE
J 0
(-5325 5475);
DISPLAY 0.574468 (-5325 5475);
PAINT GREEN (-5325 5475);
DISPLAY INVISIBLE (-5325 5475);
FORCEADD TAP..6
(-5650 5700);
FORCEPROP 3 LASTPIN (-5600 5700) SIG_NAME P5E_CPU0_P0_TX_DP<1>
J 0
(-5590 5710);
DISPLAY 0.659574 (-5590 5710);
PAINT MONO (-5590 5710);
DISPLAY INVISIBLE (-5590 5710);
FORCEPROP 1 LASTPIN (-5600 5700) BN 1
J 0
(-5652 5708);
DISPLAY 0.680851 (-5652 5708);
PAINT MONO (-5652 5708);
FORCEPROP 2 LAST CDS_LIB standard
J 0
(-5650 5700);
DISPLAY INVISIBLE (-5650 5700);
FORCEPROP 1 LAST PATH I28
J 0
(-5652 5700);
DISPLAY 0.872340 (-5652 5700);
PAINT GREEN (-5652 5700);
DISPLAY INVISIBLE (-5652 5700);
FORCEPROP 1 LAST BODY_TYPE PLUMBING
J 0
(-5650 5650);
DISPLAY 0.574468 (-5650 5650);
PAINT GREEN (-5650 5650);
DISPLAY INVISIBLE (-5650 5650);
FORCEPROP 1 LAST HDL_TAP TRUE
J 0
(-5325 5575);
DISPLAY 0.574468 (-5325 5575);
PAINT GREEN (-5325 5575);
DISPLAY INVISIBLE (-5325 5575);
FORCEADD TAP..6
(-5800 5750);
FORCEPROP 3 LASTPIN (-5750 5750) SIG_NAME P5E_CPU0_P0_TX_DN<0>
J 0
(-5740 5760);
DISPLAY 0.659574 (-5740 5760);
PAINT MONO (-5740 5760);
DISPLAY INVISIBLE (-5740 5760);
FORCEPROP 1 LASTPIN (-5750 5750) BN 0
J 0
(-5802 5758);
DISPLAY 0.680851 (-5802 5758);
PAINT MONO (-5802 5758);
FORCEPROP 2 LAST CDS_LIB standard
J 0
(-5800 5750);
DISPLAY INVISIBLE (-5800 5750);
FORCEPROP 1 LAST PATH I29
J 0
(-5802 5750);
DISPLAY 0.872340 (-5802 5750);
PAINT GREEN (-5802 5750);
DISPLAY INVISIBLE (-5802 5750);
FORCEPROP 1 LAST BODY_TYPE PLUMBING
J 0
(-5800 5700);
DISPLAY 0.574468 (-5800 5700);
PAINT GREEN (-5800 5700);
DISPLAY INVISIBLE (-5800 5700);
FORCEPROP 1 LAST HDL_TAP TRUE
J 0
(-5475 5625);
DISPLAY 0.574468 (-5475 5625);
PAINT GREEN (-5475 5625);
DISPLAY INVISIBLE (-5475 5625);
FORCEADD TAP..6
(-5800 4350);
FORCEPROP 3 LASTPIN (-5750 4350) SIG_NAME P5E_CPU0_P0_TX_DN<14>
J 0
(-5740 4360);
DISPLAY 0.659574 (-5740 4360);
PAINT MONO (-5740 4360);
DISPLAY INVISIBLE (-5740 4360);
FORCEPROP 1 LASTPIN (-5750 4350) BN 14
J 0
(-5802 4358);
DISPLAY 0.680851 (-5802 4358);
PAINT MONO (-5802 4358);
FORCEPROP 2 LAST CDS_LIB standard
J 0
(-5800 4350);
DISPLAY INVISIBLE (-5800 4350);
FORCEPROP 1 LAST PATH I3
J 0
(-5802 4350);
DISPLAY 0.872340 (-5802 4350);
PAINT GREEN (-5802 4350);
DISPLAY INVISIBLE (-5802 4350);
FORCEPROP 1 LAST BODY_TYPE PLUMBING
J 0
(-5800 4300);
DISPLAY 0.574468 (-5800 4300);
PAINT GREEN (-5800 4300);
DISPLAY INVISIBLE (-5800 4300);
FORCEPROP 1 LAST HDL_TAP TRUE
J 0
(-5475 4225);
DISPLAY 0.574468 (-5475 4225);
PAINT GREEN (-5475 4225);
DISPLAY INVISIBLE (-5475 4225);
FORCEADD TAP..6
(-5650 5800);
FORCEPROP 3 LASTPIN (-5600 5800) SIG_NAME P5E_CPU0_P0_TX_DP<0>
J 0
(-5590 5810);
DISPLAY 0.659574 (-5590 5810);
PAINT MONO (-5590 5810);
DISPLAY INVISIBLE (-5590 5810);
FORCEPROP 1 LASTPIN (-5600 5800) BN 0
J 0
(-5652 5808);
DISPLAY 0.680851 (-5652 5808);
PAINT MONO (-5652 5808);
FORCEPROP 2 LAST CDS_LIB standard
J 0
(-5650 5800);
DISPLAY INVISIBLE (-5650 5800);
FORCEPROP 1 LAST PATH I30
J 0
(-5652 5800);
DISPLAY 0.872340 (-5652 5800);
PAINT GREEN (-5652 5800);
DISPLAY INVISIBLE (-5652 5800);
FORCEPROP 1 LAST BODY_TYPE PLUMBING
J 0
(-5650 5750);
DISPLAY 0.574468 (-5650 5750);
PAINT GREEN (-5650 5750);
DISPLAY INVISIBLE (-5650 5750);
FORCEPROP 1 LAST HDL_TAP TRUE
J 0
(-5325 5675);
DISPLAY 0.574468 (-5325 5675);
PAINT GREEN (-5325 5675);
DISPLAY INVISIBLE (-5325 5675);
FORCEADD Q_CAP_DIFFBUS..2
R 2
(-4925 4300);
FORCEPROP 1 LAST LOCATION C540
J 2
(-4675 4300);
DISPLAY 0.723404 (-4675 4300);
PAINT GREEN (-4675 4300);
FORCEPROP 0 LAST $SEC 1
J 0
(-4675 4350);
DISPLAY 0.680851 (-4675 4350);
PAINT MONO (-4675 4350);
DISPLAY INVISIBLE (-4675 4350);
FORCEPROP 0 LAST CDS_SEC 1
J 0
(-4675 4350);
DISPLAY 0.680851 (-4675 4350);
DISPLAY INVISIBLE (-4675 4350);
FORCEPROP 0 LASTPIN (-4850 4300) $PN 1
J 0
(-4840 4310);
DISPLAY 0.680851 (-4840 4310);
PAINT MONO (-4840 4310);
FORCEPROP 0 LASTPIN (-5000 4300) $PN 2
J 2
(-5010 4310);
DISPLAY 0.680851 (-5010 4310);
PAINT MONO (-5010 4310);
FORCEPROP 2 LAST VALUE DIFF BUS_0.22UF
J 2
(-5050 4300);
DISPLAY 0.553191 (-5050 4300);
FORCEPROP 1 LAST CDS_LMAN_SYM_OUTLINE -25,50,25,-50
J 2
(-4925 4300);
DISPLAY 0.468085 (-4925 4300);
PAINT GREEN (-4925 4300);
DISPLAY INVISIBLE (-4925 4300);
FORCEPROP 2 LAST CDS_LIB pure_quanta
J 0
(-4925 4300);
DISPLAY INVISIBLE (-4925 4300);
FORCEPROP 1 LAST PATH I31
J 2
(-4925 4300);
DISPLAY 0.723404 (-4925 4300);
DISPLAY INVISIBLE (-4925 4300);
FORCEPROP 0 LAST PACK_TYPE C0201
J 2
(-5075 4300);
DISPLAY 0.680851 (-5075 4300);
DISPLAY INVISIBLE (-5075 4300);
FORCEPROP 1 LAST PIN_NAMES_ROTATE True
J 2
(-4925 4300);
DISPLAY 0.489362 (-4925 4300);
PAINT GREEN (-4925 4300);
DISPLAY INVISIBLE (-4925 4300);
FORCEPROP 1 LAST MATERIAL X6S
J 2
(-4775 4350);
DISPLAY 0.723404 (-4775 4350);
PAINT GREEN (-4775 4350);
DISPLAY INVISIBLE (-4775 4350);
FORCEPROP 1 LAST PART_NUMBER SP_CH4221MEE01
J 2
(-4900 4375);
DISPLAY 0.723404 (-4900 4375);
PAINT GREEN (-4900 4375);
DISPLAY INVISIBLE (-4900 4375);
FORCEPROP 0 LAST TOLERANCE 20%
J 2
(-5000 4425);
DISPLAY 0.680851 (-5000 4425);
DISPLAY INVISIBLE (-5000 4425);
FORCEPROP 0 LAST VOLTAGE 6.3V
J 2
(-5000 4475);
DISPLAY 0.680851 (-5000 4475);
DISPLAY INVISIBLE (-5000 4475);
FORCEADD Q_CAP_DIFFBUS..2
R 2
(-4925 4250);
FORCEPROP 1 LAST LOCATION C541
J 2
(-4700 4250);
DISPLAY 0.723404 (-4700 4250);
PAINT GREEN (-4700 4250);
FORCEPROP 0 LAST $SEC 1
J 0
(-4700 4300);
DISPLAY 0.680851 (-4700 4300);
PAINT MONO (-4700 4300);
DISPLAY INVISIBLE (-4700 4300);
FORCEPROP 0 LAST CDS_SEC 1
J 0
(-4700 4300);
DISPLAY 0.680851 (-4700 4300);
DISPLAY INVISIBLE (-4700 4300);
FORCEPROP 0 LASTPIN (-4850 4250) $PN 1
J 0
(-4840 4260);
DISPLAY 0.680851 (-4840 4260);
PAINT MONO (-4840 4260);
FORCEPROP 0 LASTPIN (-5000 4250) $PN 2
J 2
(-5010 4260);
DISPLAY 0.680851 (-5010 4260);
PAINT MONO (-5010 4260);
FORCEPROP 2 LAST VALUE DIFF BUS_0.22UF
J 2
(-5050 4250);
DISPLAY 0.553191 (-5050 4250);
FORCEPROP 1 LAST CDS_LMAN_SYM_OUTLINE -25,50,25,-50
J 2
(-4925 4250);
DISPLAY 0.468085 (-4925 4250);
PAINT GREEN (-4925 4250);
DISPLAY INVISIBLE (-4925 4250);
FORCEPROP 2 LAST CDS_LIB pure_quanta
J 0
(-4925 4250);
DISPLAY INVISIBLE (-4925 4250);
FORCEPROP 1 LAST PATH I32
J 2
(-4925 4250);
DISPLAY 0.723404 (-4925 4250);
DISPLAY INVISIBLE (-4925 4250);
FORCEPROP 0 LAST PACK_TYPE C0201
J 2
(-5075 4250);
DISPLAY 0.680851 (-5075 4250);
DISPLAY INVISIBLE (-5075 4250);
FORCEPROP 1 LAST PIN_NAMES_ROTATE True
J 2
(-4925 4250);
DISPLAY 0.489362 (-4925 4250);
PAINT GREEN (-4925 4250);
DISPLAY INVISIBLE (-4925 4250);
FORCEPROP 1 LAST MATERIAL X6S
J 2
(-4775 4300);
DISPLAY 0.723404 (-4775 4300);
PAINT GREEN (-4775 4300);
DISPLAY INVISIBLE (-4775 4300);
FORCEPROP 1 LAST PART_NUMBER SP_CH4221MEE01
J 2
(-4900 4325);
DISPLAY 0.723404 (-4900 4325);
PAINT GREEN (-4900 4325);
DISPLAY INVISIBLE (-4900 4325);
FORCEPROP 0 LAST TOLERANCE 20%
J 2
(-5000 4375);
DISPLAY 0.680851 (-5000 4375);
DISPLAY INVISIBLE (-5000 4375);
FORCEPROP 0 LAST VOLTAGE 6.3V
J 2
(-5000 4425);
DISPLAY 0.680851 (-5000 4425);
DISPLAY INVISIBLE (-5000 4425);
FORCEADD Q_CAP_DIFFBUS..2
R 2
(-4925 4350);
FORCEPROP 1 LAST LOCATION C539
J 2
(-4700 4350);
DISPLAY 0.723404 (-4700 4350);
PAINT GREEN (-4700 4350);
FORCEPROP 0 LAST $SEC 1
J 0
(-4700 4400);
DISPLAY 0.680851 (-4700 4400);
PAINT MONO (-4700 4400);
DISPLAY INVISIBLE (-4700 4400);
FORCEPROP 0 LAST CDS_SEC 1
J 0
(-4700 4400);
DISPLAY 0.680851 (-4700 4400);
DISPLAY INVISIBLE (-4700 4400);
FORCEPROP 0 LASTPIN (-4850 4350) $PN 1
J 0
(-4840 4360);
DISPLAY 0.680851 (-4840 4360);
PAINT MONO (-4840 4360);
FORCEPROP 0 LASTPIN (-5000 4350) $PN 2
J 2
(-5010 4360);
DISPLAY 0.680851 (-5010 4360);
PAINT MONO (-5010 4360);
FORCEPROP 2 LAST VALUE DIFF BUS_0.22UF
J 2
(-5050 4350);
DISPLAY 0.553191 (-5050 4350);
FORCEPROP 1 LAST CDS_LMAN_SYM_OUTLINE -25,50,25,-50
J 2
(-4925 4350);
DISPLAY 0.468085 (-4925 4350);
PAINT GREEN (-4925 4350);
DISPLAY INVISIBLE (-4925 4350);
FORCEPROP 2 LAST CDS_LIB pure_quanta
J 0
(-4925 4350);
DISPLAY INVISIBLE (-4925 4350);
FORCEPROP 1 LAST PATH I33
J 2
(-4925 4350);
DISPLAY 0.723404 (-4925 4350);
DISPLAY INVISIBLE (-4925 4350);
FORCEPROP 0 LAST PACK_TYPE C0201
J 2
(-5075 4350);
DISPLAY 0.680851 (-5075 4350);
DISPLAY INVISIBLE (-5075 4350);
FORCEPROP 1 LAST PIN_NAMES_ROTATE True
J 2
(-4925 4350);
DISPLAY 0.489362 (-4925 4350);
PAINT GREEN (-4925 4350);
DISPLAY INVISIBLE (-4925 4350);
FORCEPROP 1 LAST MATERIAL X6S
J 2
(-4775 4400);
DISPLAY 0.723404 (-4775 4400);
PAINT GREEN (-4775 4400);
DISPLAY INVISIBLE (-4775 4400);
FORCEPROP 1 LAST PART_NUMBER SP_CH4221MEE01
J 2
(-4900 4425);
DISPLAY 0.723404 (-4900 4425);
PAINT GREEN (-4900 4425);
DISPLAY INVISIBLE (-4900 4425);
FORCEPROP 0 LAST TOLERANCE 20%
J 2
(-5000 4475);
DISPLAY 0.680851 (-5000 4475);
DISPLAY INVISIBLE (-5000 4475);
FORCEPROP 0 LAST VOLTAGE 6.3V
J 2
(-5000 4525);
DISPLAY 0.680851 (-5000 4525);
DISPLAY INVISIBLE (-5000 4525);
FORCEADD Q_CAP_DIFFBUS..2
R 2
(-4925 4400);
FORCEPROP 1 LAST LOCATION C538
J 2
(-4700 4400);
DISPLAY 0.723404 (-4700 4400);
PAINT GREEN (-4700 4400);
FORCEPROP 0 LAST $SEC 1
J 0
(-4700 4450);
DISPLAY 0.680851 (-4700 4450);
PAINT MONO (-4700 4450);
DISPLAY INVISIBLE (-4700 4450);
FORCEPROP 0 LAST CDS_SEC 1
J 0
(-4700 4450);
DISPLAY 0.680851 (-4700 4450);
DISPLAY INVISIBLE (-4700 4450);
FORCEPROP 0 LASTPIN (-4850 4400) $PN 1
J 0
(-4840 4410);
DISPLAY 0.680851 (-4840 4410);
PAINT MONO (-4840 4410);
FORCEPROP 0 LASTPIN (-5000 4400) $PN 2
J 2
(-5010 4410);
DISPLAY 0.680851 (-5010 4410);
PAINT MONO (-5010 4410);
FORCEPROP 2 LAST VALUE DIFF BUS_0.22UF
J 2
(-5050 4400);
DISPLAY 0.553191 (-5050 4400);
FORCEPROP 1 LAST CDS_LMAN_SYM_OUTLINE -25,50,25,-50
J 2
(-4925 4400);
DISPLAY 0.468085 (-4925 4400);
PAINT GREEN (-4925 4400);
DISPLAY INVISIBLE (-4925 4400);
FORCEPROP 2 LAST CDS_LIB pure_quanta
J 0
(-4925 4400);
DISPLAY INVISIBLE (-4925 4400);
FORCEPROP 1 LAST PATH I34
J 2
(-4925 4400);
DISPLAY 0.723404 (-4925 4400);
DISPLAY INVISIBLE (-4925 4400);
FORCEPROP 0 LAST PACK_TYPE C0201
J 2
(-5075 4400);
DISPLAY 0.680851 (-5075 4400);
DISPLAY INVISIBLE (-5075 4400);
FORCEPROP 1 LAST PIN_NAMES_ROTATE True
J 2
(-4925 4400);
DISPLAY 0.489362 (-4925 4400);
PAINT GREEN (-4925 4400);
DISPLAY INVISIBLE (-4925 4400);
FORCEPROP 1 LAST MATERIAL X6S
J 2
(-4775 4450);
DISPLAY 0.723404 (-4775 4450);
PAINT GREEN (-4775 4450);
DISPLAY INVISIBLE (-4775 4450);
FORCEPROP 1 LAST PART_NUMBER SP_CH4221MEE01
J 2
(-4900 4475);
DISPLAY 0.723404 (-4900 4475);
PAINT GREEN (-4900 4475);
DISPLAY INVISIBLE (-4900 4475);
FORCEPROP 0 LAST TOLERANCE 20%
J 2
(-5000 4525);
DISPLAY 0.680851 (-5000 4525);
DISPLAY INVISIBLE (-5000 4525);
FORCEPROP 0 LAST VOLTAGE 6.3V
J 2
(-5000 4575);
DISPLAY 0.680851 (-5000 4575);
DISPLAY INVISIBLE (-5000 4575);
FORCEADD Q_CAP_DIFFBUS..2
R 2
(-4925 4450);
FORCEPROP 1 LAST LOCATION C529
J 2
(-4700 4450);
DISPLAY 0.723404 (-4700 4450);
PAINT GREEN (-4700 4450);
FORCEPROP 0 LAST $SEC 1
J 0
(-4700 4500);
DISPLAY 0.680851 (-4700 4500);
PAINT MONO (-4700 4500);
DISPLAY INVISIBLE (-4700 4500);
FORCEPROP 0 LAST CDS_SEC 1
J 0
(-4700 4500);
DISPLAY 0.680851 (-4700 4500);
DISPLAY INVISIBLE (-4700 4500);
FORCEPROP 0 LASTPIN (-4850 4450) $PN 1
J 0
(-4840 4460);
DISPLAY 0.680851 (-4840 4460);
PAINT MONO (-4840 4460);
FORCEPROP 0 LASTPIN (-5000 4450) $PN 2
J 2
(-5010 4460);
DISPLAY 0.680851 (-5010 4460);
PAINT MONO (-5010 4460);
FORCEPROP 2 LAST VALUE DIFF BUS_0.22UF
J 2
(-5050 4450);
DISPLAY 0.553191 (-5050 4450);
FORCEPROP 1 LAST CDS_LMAN_SYM_OUTLINE -25,50,25,-50
J 2
(-4925 4450);
DISPLAY 0.468085 (-4925 4450);
PAINT GREEN (-4925 4450);
DISPLAY INVISIBLE (-4925 4450);
FORCEPROP 2 LAST CDS_LIB pure_quanta
J 0
(-4925 4450);
DISPLAY INVISIBLE (-4925 4450);
FORCEPROP 1 LAST PATH I35
J 2
(-4925 4450);
DISPLAY 0.723404 (-4925 4450);
DISPLAY INVISIBLE (-4925 4450);
FORCEPROP 0 LAST VOLTAGE 6.3V
J 2
(-5000 4625);
DISPLAY 0.680851 (-5000 4625);
DISPLAY INVISIBLE (-5000 4625);
FORCEPROP 0 LAST TOLERANCE 20%
J 2
(-5000 4575);
DISPLAY 0.680851 (-5000 4575);
DISPLAY INVISIBLE (-5000 4575);
FORCEPROP 1 LAST PART_NUMBER SP_CH4221MEE01
J 2
(-4900 4525);
DISPLAY 0.723404 (-4900 4525);
PAINT GREEN (-4900 4525);
DISPLAY INVISIBLE (-4900 4525);
FORCEPROP 1 LAST MATERIAL X6S
J 2
(-4775 4500);
DISPLAY 0.723404 (-4775 4500);
PAINT GREEN (-4775 4500);
DISPLAY INVISIBLE (-4775 4500);
FORCEPROP 1 LAST PIN_NAMES_ROTATE True
J 2
(-4925 4450);
DISPLAY 0.489362 (-4925 4450);
PAINT GREEN (-4925 4450);
DISPLAY INVISIBLE (-4925 4450);
FORCEPROP 0 LAST PACK_TYPE C0201
J 2
(-5075 4450);
DISPLAY 0.680851 (-5075 4450);
DISPLAY INVISIBLE (-5075 4450);
FORCEADD Q_CAP_DIFFBUS..2
R 2
(-4925 4500);
FORCEPROP 1 LAST LOCATION C528
J 2
(-4700 4500);
DISPLAY 0.723404 (-4700 4500);
PAINT GREEN (-4700 4500);
FORCEPROP 0 LAST $SEC 1
J 0
(-4700 4550);
DISPLAY 0.680851 (-4700 4550);
PAINT MONO (-4700 4550);
DISPLAY INVISIBLE (-4700 4550);
FORCEPROP 0 LAST CDS_SEC 1
J 0
(-4700 4550);
DISPLAY 0.680851 (-4700 4550);
DISPLAY INVISIBLE (-4700 4550);
FORCEPROP 0 LASTPIN (-4850 4500) $PN 1
J 0
(-4840 4510);
DISPLAY 0.680851 (-4840 4510);
PAINT MONO (-4840 4510);
FORCEPROP 0 LASTPIN (-5000 4500) $PN 2
J 2
(-5010 4510);
DISPLAY 0.680851 (-5010 4510);
PAINT MONO (-5010 4510);
FORCEPROP 2 LAST VALUE DIFF BUS_0.22UF
J 2
(-5050 4500);
DISPLAY 0.553191 (-5050 4500);
FORCEPROP 1 LAST CDS_LMAN_SYM_OUTLINE -25,50,25,-50
J 2
(-4925 4500);
DISPLAY 0.468085 (-4925 4500);
PAINT GREEN (-4925 4500);
DISPLAY INVISIBLE (-4925 4500);
FORCEPROP 2 LAST CDS_LIB pure_quanta
J 0
(-4925 4500);
DISPLAY INVISIBLE (-4925 4500);
FORCEPROP 1 LAST PATH I36
J 2
(-4925 4500);
DISPLAY 0.723404 (-4925 4500);
DISPLAY INVISIBLE (-4925 4500);
FORCEPROP 0 LAST VOLTAGE 6.3V
J 2
(-5000 4675);
DISPLAY 0.680851 (-5000 4675);
DISPLAY INVISIBLE (-5000 4675);
FORCEPROP 0 LAST TOLERANCE 20%
J 2
(-5000 4625);
DISPLAY 0.680851 (-5000 4625);
DISPLAY INVISIBLE (-5000 4625);
FORCEPROP 1 LAST PART_NUMBER SP_CH4221MEE01
J 2
(-4900 4575);
DISPLAY 0.723404 (-4900 4575);
PAINT GREEN (-4900 4575);
DISPLAY INVISIBLE (-4900 4575);
FORCEPROP 1 LAST MATERIAL X6S
J 2
(-4775 4550);
DISPLAY 0.723404 (-4775 4550);
PAINT GREEN (-4775 4550);
DISPLAY INVISIBLE (-4775 4550);
FORCEPROP 1 LAST PIN_NAMES_ROTATE True
J 2
(-4925 4500);
DISPLAY 0.489362 (-4925 4500);
PAINT GREEN (-4925 4500);
DISPLAY INVISIBLE (-4925 4500);
FORCEPROP 0 LAST PACK_TYPE C0201
J 2
(-5075 4500);
DISPLAY 0.680851 (-5075 4500);
DISPLAY INVISIBLE (-5075 4500);
FORCEADD Q_CAP_DIFFBUS..2
R 2
(-4925 4550);
FORCEPROP 1 LAST LOCATION C526
J 2
(-4700 4550);
DISPLAY 0.723404 (-4700 4550);
PAINT GREEN (-4700 4550);
FORCEPROP 0 LAST $SEC 1
J 0
(-4700 4600);
DISPLAY 0.680851 (-4700 4600);
PAINT MONO (-4700 4600);
DISPLAY INVISIBLE (-4700 4600);
FORCEPROP 0 LAST CDS_SEC 1
J 0
(-4700 4600);
DISPLAY 0.680851 (-4700 4600);
DISPLAY INVISIBLE (-4700 4600);
FORCEPROP 0 LASTPIN (-4850 4550) $PN 1
J 0
(-4840 4560);
DISPLAY 0.680851 (-4840 4560);
PAINT MONO (-4840 4560);
FORCEPROP 0 LASTPIN (-5000 4550) $PN 2
J 2
(-5010 4560);
DISPLAY 0.680851 (-5010 4560);
PAINT MONO (-5010 4560);
FORCEPROP 2 LAST VALUE DIFF BUS_0.22UF
J 2
(-5050 4550);
DISPLAY 0.553191 (-5050 4550);
FORCEPROP 1 LAST CDS_LMAN_SYM_OUTLINE -25,50,25,-50
J 2
(-4925 4550);
DISPLAY 0.468085 (-4925 4550);
PAINT GREEN (-4925 4550);
DISPLAY INVISIBLE (-4925 4550);
FORCEPROP 2 LAST CDS_LIB pure_quanta
J 0
(-4925 4550);
DISPLAY INVISIBLE (-4925 4550);
FORCEPROP 1 LAST PATH I37
J 2
(-4925 4550);
DISPLAY 0.723404 (-4925 4550);
DISPLAY INVISIBLE (-4925 4550);
FORCEPROP 0 LAST VOLTAGE 6.3V
J 2
(-5000 4725);
DISPLAY 0.680851 (-5000 4725);
DISPLAY INVISIBLE (-5000 4725);
FORCEPROP 0 LAST TOLERANCE 20%
J 2
(-5000 4675);
DISPLAY 0.680851 (-5000 4675);
DISPLAY INVISIBLE (-5000 4675);
FORCEPROP 1 LAST PART_NUMBER SP_CH4221MEE01
J 2
(-4900 4625);
DISPLAY 0.723404 (-4900 4625);
PAINT GREEN (-4900 4625);
DISPLAY INVISIBLE (-4900 4625);
FORCEPROP 1 LAST MATERIAL X6S
J 2
(-4775 4600);
DISPLAY 0.723404 (-4775 4600);
PAINT GREEN (-4775 4600);
DISPLAY INVISIBLE (-4775 4600);
FORCEPROP 1 LAST PIN_NAMES_ROTATE True
J 2
(-4925 4550);
DISPLAY 0.489362 (-4925 4550);
PAINT GREEN (-4925 4550);
DISPLAY INVISIBLE (-4925 4550);
FORCEPROP 0 LAST PACK_TYPE C0201
J 2
(-5075 4550);
DISPLAY 0.680851 (-5075 4550);
DISPLAY INVISIBLE (-5075 4550);
FORCEADD Q_CAP_DIFFBUS..2
R 2
(-4925 4650);
FORCEPROP 1 LAST LOCATION C524
J 2
(-4700 4650);
DISPLAY 0.723404 (-4700 4650);
PAINT GREEN (-4700 4650);
FORCEPROP 0 LAST $SEC 1
J 0
(-4700 4700);
DISPLAY 0.680851 (-4700 4700);
PAINT MONO (-4700 4700);
DISPLAY INVISIBLE (-4700 4700);
FORCEPROP 0 LAST CDS_SEC 1
J 0
(-4700 4700);
DISPLAY 0.680851 (-4700 4700);
DISPLAY INVISIBLE (-4700 4700);
FORCEPROP 0 LASTPIN (-4850 4650) $PN 1
J 0
(-4840 4660);
DISPLAY 0.680851 (-4840 4660);
PAINT MONO (-4840 4660);
FORCEPROP 0 LASTPIN (-5000 4650) $PN 2
J 2
(-5010 4660);
DISPLAY 0.680851 (-5010 4660);
PAINT MONO (-5010 4660);
FORCEPROP 2 LAST VALUE DIFF BUS_0.22UF
J 2
(-5050 4650);
DISPLAY 0.553191 (-5050 4650);
FORCEPROP 1 LAST CDS_LMAN_SYM_OUTLINE -25,50,25,-50
J 2
(-4925 4650);
DISPLAY 0.468085 (-4925 4650);
PAINT GREEN (-4925 4650);
DISPLAY INVISIBLE (-4925 4650);
FORCEPROP 2 LAST CDS_LIB pure_quanta
J 0
(-4925 4650);
DISPLAY INVISIBLE (-4925 4650);
FORCEPROP 1 LAST PATH I38
J 2
(-4925 4650);
DISPLAY 0.723404 (-4925 4650);
DISPLAY INVISIBLE (-4925 4650);
FORCEPROP 0 LAST VOLTAGE 6.3V
J 2
(-5000 4825);
DISPLAY 0.680851 (-5000 4825);
DISPLAY INVISIBLE (-5000 4825);
FORCEPROP 0 LAST TOLERANCE 20%
J 2
(-5000 4775);
DISPLAY 0.680851 (-5000 4775);
DISPLAY INVISIBLE (-5000 4775);
FORCEPROP 1 LAST PART_NUMBER SP_CH4221MEE01
J 2
(-4900 4725);
DISPLAY 0.723404 (-4900 4725);
PAINT GREEN (-4900 4725);
DISPLAY INVISIBLE (-4900 4725);
FORCEPROP 1 LAST MATERIAL X6S
J 2
(-4775 4700);
DISPLAY 0.723404 (-4775 4700);
PAINT GREEN (-4775 4700);
DISPLAY INVISIBLE (-4775 4700);
FORCEPROP 1 LAST PIN_NAMES_ROTATE True
J 2
(-4925 4650);
DISPLAY 0.489362 (-4925 4650);
PAINT GREEN (-4925 4650);
DISPLAY INVISIBLE (-4925 4650);
FORCEPROP 0 LAST PACK_TYPE C0201
J 2
(-5075 4650);
DISPLAY 0.680851 (-5075 4650);
DISPLAY INVISIBLE (-5075 4650);
FORCEADD Q_CAP_DIFFBUS..2
R 2
(-4925 4600);
FORCEPROP 1 LAST LOCATION C525
J 2
(-4725 4600);
DISPLAY 0.723404 (-4725 4600);
PAINT GREEN (-4725 4600);
FORCEPROP 0 LAST $SEC 1
J 0
(-4725 4650);
DISPLAY 0.680851 (-4725 4650);
PAINT MONO (-4725 4650);
DISPLAY INVISIBLE (-4725 4650);
FORCEPROP 0 LAST CDS_SEC 1
J 0
(-4725 4650);
DISPLAY 0.680851 (-4725 4650);
DISPLAY INVISIBLE (-4725 4650);
FORCEPROP 0 LASTPIN (-4850 4600) $PN 1
J 0
(-4840 4610);
DISPLAY 0.680851 (-4840 4610);
PAINT MONO (-4840 4610);
FORCEPROP 0 LASTPIN (-5000 4600) $PN 2
J 2
(-5010 4610);
DISPLAY 0.680851 (-5010 4610);
PAINT MONO (-5010 4610);
FORCEPROP 2 LAST VALUE DIFF BUS_0.22UF
J 2
(-5050 4600);
DISPLAY 0.553191 (-5050 4600);
FORCEPROP 1 LAST CDS_LMAN_SYM_OUTLINE -25,50,25,-50
J 2
(-4925 4600);
DISPLAY 0.468085 (-4925 4600);
PAINT GREEN (-4925 4600);
DISPLAY INVISIBLE (-4925 4600);
FORCEPROP 2 LAST CDS_LIB pure_quanta
J 0
(-4925 4600);
DISPLAY INVISIBLE (-4925 4600);
FORCEPROP 1 LAST PATH I39
J 2
(-4925 4600);
DISPLAY 0.723404 (-4925 4600);
DISPLAY INVISIBLE (-4925 4600);
FORCEPROP 0 LAST VOLTAGE 6.3V
J 2
(-5000 4775);
DISPLAY 0.680851 (-5000 4775);
DISPLAY INVISIBLE (-5000 4775);
FORCEPROP 0 LAST TOLERANCE 20%
J 2
(-5000 4725);
DISPLAY 0.680851 (-5000 4725);
DISPLAY INVISIBLE (-5000 4725);
FORCEPROP 1 LAST PART_NUMBER SP_CH4221MEE01
J 2
(-4900 4675);
DISPLAY 0.723404 (-4900 4675);
PAINT GREEN (-4900 4675);
DISPLAY INVISIBLE (-4900 4675);
FORCEPROP 1 LAST MATERIAL X6S
J 2
(-4775 4650);
DISPLAY 0.723404 (-4775 4650);
PAINT GREEN (-4775 4650);
DISPLAY INVISIBLE (-4775 4650);
FORCEPROP 1 LAST PIN_NAMES_ROTATE True
J 2
(-4925 4600);
DISPLAY 0.489362 (-4925 4600);
PAINT GREEN (-4925 4600);
DISPLAY INVISIBLE (-4925 4600);
FORCEPROP 0 LAST PACK_TYPE C0201
J 2
(-5075 4600);
DISPLAY 0.680851 (-5075 4600);
DISPLAY INVISIBLE (-5075 4600);
FORCEADD TAP..6
(-5800 4550);
FORCEPROP 3 LASTPIN (-5750 4550) SIG_NAME P5E_CPU0_P0_TX_DN<12>
J 0
(-5740 4560);
DISPLAY 0.659574 (-5740 4560);
PAINT MONO (-5740 4560);
DISPLAY INVISIBLE (-5740 4560);
FORCEPROP 1 LASTPIN (-5750 4550) BN 12
J 0
(-5802 4558);
DISPLAY 0.680851 (-5802 4558);
PAINT MONO (-5802 4558);
FORCEPROP 2 LAST CDS_LIB standard
J 0
(-5800 4550);
DISPLAY INVISIBLE (-5800 4550);
FORCEPROP 1 LAST PATH I4
J 0
(-5802 4550);
DISPLAY 0.872340 (-5802 4550);
PAINT GREEN (-5802 4550);
DISPLAY INVISIBLE (-5802 4550);
FORCEPROP 1 LAST BODY_TYPE PLUMBING
J 0
(-5800 4500);
DISPLAY 0.574468 (-5800 4500);
PAINT GREEN (-5800 4500);
DISPLAY INVISIBLE (-5800 4500);
FORCEPROP 1 LAST HDL_TAP TRUE
J 0
(-5475 4425);
DISPLAY 0.574468 (-5475 4425);
PAINT GREEN (-5475 4425);
DISPLAY INVISIBLE (-5475 4425);
FORCEADD Q_CAP_DIFFBUS..2
R 2
(-4925 4700);
FORCEPROP 1 LAST LOCATION C523
J 2
(-4700 4700);
DISPLAY 0.723404 (-4700 4700);
PAINT GREEN (-4700 4700);
FORCEPROP 0 LAST $SEC 1
J 0
(-4700 4750);
DISPLAY 0.680851 (-4700 4750);
PAINT MONO (-4700 4750);
DISPLAY INVISIBLE (-4700 4750);
FORCEPROP 0 LAST CDS_SEC 1
J 0
(-4700 4750);
DISPLAY 0.680851 (-4700 4750);
DISPLAY INVISIBLE (-4700 4750);
FORCEPROP 0 LASTPIN (-4850 4700) $PN 1
J 0
(-4840 4710);
DISPLAY 0.680851 (-4840 4710);
PAINT MONO (-4840 4710);
FORCEPROP 0 LASTPIN (-5000 4700) $PN 2
J 2
(-5010 4710);
DISPLAY 0.680851 (-5010 4710);
PAINT MONO (-5010 4710);
FORCEPROP 2 LAST VALUE DIFF BUS_0.22UF
J 2
(-5050 4700);
DISPLAY 0.553191 (-5050 4700);
FORCEPROP 1 LAST CDS_LMAN_SYM_OUTLINE -25,50,25,-50
J 2
(-4925 4700);
DISPLAY 0.468085 (-4925 4700);
PAINT GREEN (-4925 4700);
DISPLAY INVISIBLE (-4925 4700);
FORCEPROP 2 LAST CDS_LIB pure_quanta
J 0
(-4925 4700);
DISPLAY INVISIBLE (-4925 4700);
FORCEPROP 1 LAST PATH I40
J 2
(-4925 4700);
DISPLAY 0.723404 (-4925 4700);
DISPLAY INVISIBLE (-4925 4700);
FORCEPROP 0 LAST VOLTAGE 6.3V
J 2
(-5000 4875);
DISPLAY 0.680851 (-5000 4875);
DISPLAY INVISIBLE (-5000 4875);
FORCEPROP 0 LAST TOLERANCE 20%
J 2
(-5000 4825);
DISPLAY 0.680851 (-5000 4825);
DISPLAY INVISIBLE (-5000 4825);
FORCEPROP 1 LAST PART_NUMBER SP_CH4221MEE01
J 2
(-4900 4775);
DISPLAY 0.723404 (-4900 4775);
PAINT GREEN (-4900 4775);
DISPLAY INVISIBLE (-4900 4775);
FORCEPROP 1 LAST MATERIAL X6S
J 2
(-4775 4750);
DISPLAY 0.723404 (-4775 4750);
PAINT GREEN (-4775 4750);
DISPLAY INVISIBLE (-4775 4750);
FORCEPROP 1 LAST PIN_NAMES_ROTATE True
J 2
(-4925 4700);
DISPLAY 0.489362 (-4925 4700);
PAINT GREEN (-4925 4700);
DISPLAY INVISIBLE (-4925 4700);
FORCEPROP 0 LAST PACK_TYPE C0201
J 2
(-5075 4700);
DISPLAY 0.680851 (-5075 4700);
DISPLAY INVISIBLE (-5075 4700);
FORCEADD Q_CAP_DIFFBUS..2
R 2
(-4925 4800);
FORCEPROP 1 LAST LOCATION C521
J 2
(-4700 4800);
DISPLAY 0.723404 (-4700 4800);
PAINT GREEN (-4700 4800);
FORCEPROP 0 LAST $SEC 1
J 0
(-4700 4850);
DISPLAY 0.680851 (-4700 4850);
PAINT MONO (-4700 4850);
DISPLAY INVISIBLE (-4700 4850);
FORCEPROP 0 LAST CDS_SEC 1
J 0
(-4700 4850);
DISPLAY 0.680851 (-4700 4850);
DISPLAY INVISIBLE (-4700 4850);
FORCEPROP 0 LASTPIN (-4850 4800) $PN 1
J 0
(-4840 4810);
DISPLAY 0.680851 (-4840 4810);
PAINT MONO (-4840 4810);
FORCEPROP 0 LASTPIN (-5000 4800) $PN 2
J 2
(-5010 4810);
DISPLAY 0.680851 (-5010 4810);
PAINT MONO (-5010 4810);
FORCEPROP 2 LAST VALUE DIFF BUS_0.22UF
J 2
(-5050 4800);
DISPLAY 0.553191 (-5050 4800);
FORCEPROP 1 LAST CDS_LMAN_SYM_OUTLINE -25,50,25,-50
J 2
(-4925 4800);
DISPLAY 0.468085 (-4925 4800);
PAINT GREEN (-4925 4800);
DISPLAY INVISIBLE (-4925 4800);
FORCEPROP 2 LAST CDS_LIB pure_quanta
J 0
(-4925 4800);
DISPLAY INVISIBLE (-4925 4800);
FORCEPROP 1 LAST PATH I41
J 2
(-4925 4800);
DISPLAY 0.723404 (-4925 4800);
DISPLAY INVISIBLE (-4925 4800);
FORCEPROP 0 LAST VOLTAGE 6.3V
J 2
(-5000 4975);
DISPLAY 0.680851 (-5000 4975);
DISPLAY INVISIBLE (-5000 4975);
FORCEPROP 0 LAST TOLERANCE 20%
J 2
(-5000 4925);
DISPLAY 0.680851 (-5000 4925);
DISPLAY INVISIBLE (-5000 4925);
FORCEPROP 1 LAST PART_NUMBER SP_CH4221MEE01
J 2
(-4900 4875);
DISPLAY 0.723404 (-4900 4875);
PAINT GREEN (-4900 4875);
DISPLAY INVISIBLE (-4900 4875);
FORCEPROP 1 LAST MATERIAL X6S
J 2
(-4775 4850);
DISPLAY 0.723404 (-4775 4850);
PAINT GREEN (-4775 4850);
DISPLAY INVISIBLE (-4775 4850);
FORCEPROP 1 LAST PIN_NAMES_ROTATE True
J 2
(-4925 4800);
DISPLAY 0.489362 (-4925 4800);
PAINT GREEN (-4925 4800);
DISPLAY INVISIBLE (-4925 4800);
FORCEPROP 0 LAST PACK_TYPE C0201
J 2
(-5075 4800);
DISPLAY 0.680851 (-5075 4800);
DISPLAY INVISIBLE (-5075 4800);
FORCEADD Q_CAP_DIFFBUS..2
R 2
(-4925 4750);
FORCEPROP 1 LAST LOCATION C522
J 2
(-4725 4750);
DISPLAY 0.723404 (-4725 4750);
PAINT GREEN (-4725 4750);
FORCEPROP 0 LAST $SEC 1
J 0
(-4725 4800);
DISPLAY 0.680851 (-4725 4800);
PAINT MONO (-4725 4800);
DISPLAY INVISIBLE (-4725 4800);
FORCEPROP 0 LAST CDS_SEC 1
J 0
(-4725 4800);
DISPLAY 0.680851 (-4725 4800);
DISPLAY INVISIBLE (-4725 4800);
FORCEPROP 0 LASTPIN (-4850 4750) $PN 1
J 0
(-4840 4760);
DISPLAY 0.680851 (-4840 4760);
PAINT MONO (-4840 4760);
FORCEPROP 0 LASTPIN (-5000 4750) $PN 2
J 2
(-5010 4760);
DISPLAY 0.680851 (-5010 4760);
PAINT MONO (-5010 4760);
FORCEPROP 2 LAST VALUE DIFF BUS_0.22UF
J 2
(-5050 4750);
DISPLAY 0.553191 (-5050 4750);
FORCEPROP 1 LAST CDS_LMAN_SYM_OUTLINE -25,50,25,-50
J 2
(-4925 4750);
DISPLAY 0.468085 (-4925 4750);
PAINT GREEN (-4925 4750);
DISPLAY INVISIBLE (-4925 4750);
FORCEPROP 2 LAST CDS_LIB pure_quanta
J 0
(-4925 4750);
DISPLAY INVISIBLE (-4925 4750);
FORCEPROP 1 LAST PATH I42
J 2
(-4925 4750);
DISPLAY 0.723404 (-4925 4750);
DISPLAY INVISIBLE (-4925 4750);
FORCEPROP 0 LAST PACK_TYPE C0201
J 2
(-5075 4750);
DISPLAY 0.680851 (-5075 4750);
DISPLAY INVISIBLE (-5075 4750);
FORCEPROP 1 LAST PIN_NAMES_ROTATE True
J 2
(-4925 4750);
DISPLAY 0.489362 (-4925 4750);
PAINT GREEN (-4925 4750);
DISPLAY INVISIBLE (-4925 4750);
FORCEPROP 1 LAST MATERIAL X6S
J 2
(-4775 4800);
DISPLAY 0.723404 (-4775 4800);
PAINT GREEN (-4775 4800);
DISPLAY INVISIBLE (-4775 4800);
FORCEPROP 1 LAST PART_NUMBER SP_CH4221MEE01
J 2
(-4900 4825);
DISPLAY 0.723404 (-4900 4825);
PAINT GREEN (-4900 4825);
DISPLAY INVISIBLE (-4900 4825);
FORCEPROP 0 LAST TOLERANCE 20%
J 2
(-5000 4875);
DISPLAY 0.680851 (-5000 4875);
DISPLAY INVISIBLE (-5000 4875);
FORCEPROP 0 LAST VOLTAGE 6.3V
J 2
(-5000 4925);
DISPLAY 0.680851 (-5000 4925);
DISPLAY INVISIBLE (-5000 4925);
FORCEADD Q_CAP_DIFFBUS..2
R 2
(-4925 4900);
FORCEPROP 1 LAST LOCATION C519
J 2
(-4725 4900);
DISPLAY 0.723404 (-4725 4900);
PAINT GREEN (-4725 4900);
FORCEPROP 0 LAST $SEC 1
J 0
(-4725 4950);
DISPLAY 0.680851 (-4725 4950);
PAINT MONO (-4725 4950);
DISPLAY INVISIBLE (-4725 4950);
FORCEPROP 0 LAST CDS_SEC 1
J 0
(-4725 4950);
DISPLAY 0.680851 (-4725 4950);
DISPLAY INVISIBLE (-4725 4950);
FORCEPROP 0 LASTPIN (-4850 4900) $PN 1
J 0
(-4840 4910);
DISPLAY 0.680851 (-4840 4910);
PAINT MONO (-4840 4910);
FORCEPROP 0 LASTPIN (-5000 4900) $PN 2
J 2
(-5010 4910);
DISPLAY 0.680851 (-5010 4910);
PAINT MONO (-5010 4910);
FORCEPROP 2 LAST VALUE DIFF BUS_0.22UF
J 2
(-5050 4900);
DISPLAY 0.553191 (-5050 4900);
FORCEPROP 1 LAST CDS_LMAN_SYM_OUTLINE -25,50,25,-50
J 2
(-4925 4900);
DISPLAY 0.468085 (-4925 4900);
PAINT GREEN (-4925 4900);
DISPLAY INVISIBLE (-4925 4900);
FORCEPROP 2 LAST CDS_LIB pure_quanta
J 0
(-4925 4900);
DISPLAY INVISIBLE (-4925 4900);
FORCEPROP 1 LAST PATH I43
J 2
(-4925 4900);
DISPLAY 0.723404 (-4925 4900);
DISPLAY INVISIBLE (-4925 4900);
FORCEPROP 0 LAST VOLTAGE 6.3V
J 2
(-5000 5075);
DISPLAY 0.680851 (-5000 5075);
DISPLAY INVISIBLE (-5000 5075);
FORCEPROP 0 LAST TOLERANCE 20%
J 2
(-5000 5025);
DISPLAY 0.680851 (-5000 5025);
DISPLAY INVISIBLE (-5000 5025);
FORCEPROP 1 LAST PART_NUMBER SP_CH4221MEE01
J 2
(-4900 4975);
DISPLAY 0.723404 (-4900 4975);
PAINT GREEN (-4900 4975);
DISPLAY INVISIBLE (-4900 4975);
FORCEPROP 1 LAST MATERIAL X6S
J 2
(-4775 4950);
DISPLAY 0.723404 (-4775 4950);
PAINT GREEN (-4775 4950);
DISPLAY INVISIBLE (-4775 4950);
FORCEPROP 1 LAST PIN_NAMES_ROTATE True
J 2
(-4925 4900);
DISPLAY 0.489362 (-4925 4900);
PAINT GREEN (-4925 4900);
DISPLAY INVISIBLE (-4925 4900);
FORCEPROP 0 LAST PACK_TYPE C0201
J 2
(-5075 4900);
DISPLAY 0.680851 (-5075 4900);
DISPLAY INVISIBLE (-5075 4900);
FORCEADD Q_CAP_DIFFBUS..2
R 2
(-4925 4950);
FORCEPROP 1 LAST LOCATION C517
J 2
(-4725 4950);
DISPLAY 0.723404 (-4725 4950);
PAINT GREEN (-4725 4950);
FORCEPROP 0 LAST $SEC 1
J 0
(-4725 5000);
DISPLAY 0.680851 (-4725 5000);
PAINT MONO (-4725 5000);
DISPLAY INVISIBLE (-4725 5000);
FORCEPROP 0 LAST CDS_SEC 1
J 0
(-4725 5000);
DISPLAY 0.680851 (-4725 5000);
DISPLAY INVISIBLE (-4725 5000);
FORCEPROP 0 LASTPIN (-4850 4950) $PN 1
J 0
(-4840 4960);
DISPLAY 0.680851 (-4840 4960);
PAINT MONO (-4840 4960);
FORCEPROP 0 LASTPIN (-5000 4950) $PN 2
J 2
(-5010 4960);
DISPLAY 0.680851 (-5010 4960);
PAINT MONO (-5010 4960);
FORCEPROP 2 LAST VALUE DIFF BUS_0.22UF
J 2
(-5050 4950);
DISPLAY 0.553191 (-5050 4950);
FORCEPROP 1 LAST CDS_LMAN_SYM_OUTLINE -25,50,25,-50
J 2
(-4925 4950);
DISPLAY 0.468085 (-4925 4950);
PAINT GREEN (-4925 4950);
DISPLAY INVISIBLE (-4925 4950);
FORCEPROP 2 LAST CDS_LIB pure_quanta
J 0
(-4925 4950);
DISPLAY INVISIBLE (-4925 4950);
FORCEPROP 1 LAST PATH I44
J 2
(-4925 4950);
DISPLAY 0.723404 (-4925 4950);
DISPLAY INVISIBLE (-4925 4950);
FORCEPROP 0 LAST PACK_TYPE C0201
J 2
(-5075 4950);
DISPLAY 0.680851 (-5075 4950);
DISPLAY INVISIBLE (-5075 4950);
FORCEPROP 1 LAST PIN_NAMES_ROTATE True
J 2
(-4925 4950);
DISPLAY 0.489362 (-4925 4950);
PAINT GREEN (-4925 4950);
DISPLAY INVISIBLE (-4925 4950);
FORCEPROP 1 LAST MATERIAL X6S
J 2
(-4775 5000);
DISPLAY 0.723404 (-4775 5000);
PAINT GREEN (-4775 5000);
DISPLAY INVISIBLE (-4775 5000);
FORCEPROP 1 LAST PART_NUMBER SP_CH4221MEE01
J 2
(-4900 5025);
DISPLAY 0.723404 (-4900 5025);
PAINT GREEN (-4900 5025);
DISPLAY INVISIBLE (-4900 5025);
FORCEPROP 0 LAST TOLERANCE 20%
J 2
(-5000 5075);
DISPLAY 0.680851 (-5000 5075);
DISPLAY INVISIBLE (-5000 5075);
FORCEPROP 0 LAST VOLTAGE 6.3V
J 2
(-5000 5125);
DISPLAY 0.680851 (-5000 5125);
DISPLAY INVISIBLE (-5000 5125);
FORCEADD Q_CAP_DIFFBUS..2
R 2
(-4925 5050);
FORCEPROP 1 LAST LOCATION C515
J 2
(-4725 5050);
DISPLAY 0.723404 (-4725 5050);
PAINT GREEN (-4725 5050);
FORCEPROP 0 LAST $SEC 1
J 0
(-4725 5100);
DISPLAY 0.680851 (-4725 5100);
PAINT MONO (-4725 5100);
DISPLAY INVISIBLE (-4725 5100);
FORCEPROP 0 LAST CDS_SEC 1
J 0
(-4725 5100);
DISPLAY 0.680851 (-4725 5100);
DISPLAY INVISIBLE (-4725 5100);
FORCEPROP 0 LASTPIN (-4850 5050) $PN 1
J 0
(-4840 5060);
DISPLAY 0.680851 (-4840 5060);
PAINT MONO (-4840 5060);
FORCEPROP 0 LASTPIN (-5000 5050) $PN 2
J 2
(-5010 5060);
DISPLAY 0.680851 (-5010 5060);
PAINT MONO (-5010 5060);
FORCEPROP 2 LAST VALUE DIFF BUS_0.22UF
J 2
(-5050 5050);
DISPLAY 0.553191 (-5050 5050);
FORCEPROP 1 LAST CDS_LMAN_SYM_OUTLINE -25,50,25,-50
J 2
(-4925 5050);
DISPLAY 0.468085 (-4925 5050);
PAINT GREEN (-4925 5050);
DISPLAY INVISIBLE (-4925 5050);
FORCEPROP 2 LAST CDS_LIB pure_quanta
J 0
(-4925 5050);
DISPLAY INVISIBLE (-4925 5050);
FORCEPROP 1 LAST PATH I45
J 2
(-4925 5050);
DISPLAY 0.723404 (-4925 5050);
DISPLAY INVISIBLE (-4925 5050);
FORCEPROP 0 LAST VOLTAGE 6.3V
J 2
(-5000 5225);
DISPLAY 0.680851 (-5000 5225);
DISPLAY INVISIBLE (-5000 5225);
FORCEPROP 0 LAST TOLERANCE 20%
J 2
(-5000 5175);
DISPLAY 0.680851 (-5000 5175);
DISPLAY INVISIBLE (-5000 5175);
FORCEPROP 1 LAST PART_NUMBER SP_CH4221MEE01
J 2
(-4900 5125);
DISPLAY 0.723404 (-4900 5125);
PAINT GREEN (-4900 5125);
DISPLAY INVISIBLE (-4900 5125);
FORCEPROP 1 LAST MATERIAL X6S
J 2
(-4775 5100);
DISPLAY 0.723404 (-4775 5100);
PAINT GREEN (-4775 5100);
DISPLAY INVISIBLE (-4775 5100);
FORCEPROP 1 LAST PIN_NAMES_ROTATE True
J 2
(-4925 5050);
DISPLAY 0.489362 (-4925 5050);
PAINT GREEN (-4925 5050);
DISPLAY INVISIBLE (-4925 5050);
FORCEPROP 0 LAST PACK_TYPE C0201
J 2
(-5075 5050);
DISPLAY 0.680851 (-5075 5050);
DISPLAY INVISIBLE (-5075 5050);
FORCEADD Q_CAP_DIFFBUS..2
R 2
(-4925 5000);
FORCEPROP 1 LAST LOCATION C516
J 2
(-4725 5000);
DISPLAY 0.723404 (-4725 5000);
PAINT GREEN (-4725 5000);
FORCEPROP 0 LAST $SEC 1
J 0
(-4725 5050);
DISPLAY 0.680851 (-4725 5050);
PAINT MONO (-4725 5050);
DISPLAY INVISIBLE (-4725 5050);
FORCEPROP 0 LAST CDS_SEC 1
J 0
(-4725 5050);
DISPLAY 0.680851 (-4725 5050);
DISPLAY INVISIBLE (-4725 5050);
FORCEPROP 0 LASTPIN (-4850 5000) $PN 1
J 0
(-4840 5010);
DISPLAY 0.680851 (-4840 5010);
PAINT MONO (-4840 5010);
FORCEPROP 0 LASTPIN (-5000 5000) $PN 2
J 2
(-5010 5010);
DISPLAY 0.680851 (-5010 5010);
PAINT MONO (-5010 5010);
FORCEPROP 2 LAST VALUE DIFF BUS_0.22UF
J 2
(-5050 5000);
DISPLAY 0.553191 (-5050 5000);
FORCEPROP 1 LAST CDS_LMAN_SYM_OUTLINE -25,50,25,-50
J 2
(-4925 5000);
DISPLAY 0.468085 (-4925 5000);
PAINT GREEN (-4925 5000);
DISPLAY INVISIBLE (-4925 5000);
FORCEPROP 2 LAST CDS_LIB pure_quanta
J 0
(-4925 5000);
DISPLAY INVISIBLE (-4925 5000);
FORCEPROP 1 LAST PATH I46
J 2
(-4925 5000);
DISPLAY 0.723404 (-4925 5000);
DISPLAY INVISIBLE (-4925 5000);
FORCEPROP 0 LAST VOLTAGE 6.3V
J 2
(-5000 5175);
DISPLAY 0.680851 (-5000 5175);
DISPLAY INVISIBLE (-5000 5175);
FORCEPROP 0 LAST TOLERANCE 20%
J 2
(-5000 5125);
DISPLAY 0.680851 (-5000 5125);
DISPLAY INVISIBLE (-5000 5125);
FORCEPROP 1 LAST PART_NUMBER SP_CH4221MEE01
J 2
(-4900 5075);
DISPLAY 0.723404 (-4900 5075);
PAINT GREEN (-4900 5075);
DISPLAY INVISIBLE (-4900 5075);
FORCEPROP 1 LAST MATERIAL X6S
J 2
(-4775 5050);
DISPLAY 0.723404 (-4775 5050);
PAINT GREEN (-4775 5050);
DISPLAY INVISIBLE (-4775 5050);
FORCEPROP 1 LAST PIN_NAMES_ROTATE True
J 2
(-4925 5000);
DISPLAY 0.489362 (-4925 5000);
PAINT GREEN (-4925 5000);
DISPLAY INVISIBLE (-4925 5000);
FORCEPROP 0 LAST PACK_TYPE C0201
J 2
(-5075 5000);
DISPLAY 0.680851 (-5075 5000);
DISPLAY INVISIBLE (-5075 5000);
FORCEADD Q_CAP_DIFFBUS..2
R 2
(-4925 5150);
FORCEPROP 1 LAST LOCATION C513
J 2
(-4725 5150);
DISPLAY 0.723404 (-4725 5150);
PAINT GREEN (-4725 5150);
FORCEPROP 0 LAST $SEC 1
J 0
(-4725 5200);
DISPLAY 0.680851 (-4725 5200);
PAINT MONO (-4725 5200);
DISPLAY INVISIBLE (-4725 5200);
FORCEPROP 0 LAST CDS_SEC 1
J 0
(-4725 5200);
DISPLAY 0.680851 (-4725 5200);
DISPLAY INVISIBLE (-4725 5200);
FORCEPROP 0 LASTPIN (-4850 5150) $PN 1
J 0
(-4840 5160);
DISPLAY 0.680851 (-4840 5160);
PAINT MONO (-4840 5160);
FORCEPROP 0 LASTPIN (-5000 5150) $PN 2
J 2
(-5010 5160);
DISPLAY 0.680851 (-5010 5160);
PAINT MONO (-5010 5160);
FORCEPROP 2 LAST VALUE DIFF BUS_0.22UF
J 2
(-5050 5150);
DISPLAY 0.553191 (-5050 5150);
FORCEPROP 1 LAST CDS_LMAN_SYM_OUTLINE -25,50,25,-50
J 2
(-4925 5150);
DISPLAY 0.468085 (-4925 5150);
PAINT GREEN (-4925 5150);
DISPLAY INVISIBLE (-4925 5150);
FORCEPROP 2 LAST CDS_LIB pure_quanta
J 0
(-4925 5150);
DISPLAY INVISIBLE (-4925 5150);
FORCEPROP 1 LAST PATH I47
J 2
(-4925 5150);
DISPLAY 0.723404 (-4925 5150);
DISPLAY INVISIBLE (-4925 5150);
FORCEPROP 0 LAST VOLTAGE 6.3V
J 2
(-5000 5325);
DISPLAY 0.680851 (-5000 5325);
DISPLAY INVISIBLE (-5000 5325);
FORCEPROP 0 LAST TOLERANCE 20%
J 2
(-5000 5275);
DISPLAY 0.680851 (-5000 5275);
DISPLAY INVISIBLE (-5000 5275);
FORCEPROP 1 LAST PART_NUMBER SP_CH4221MEE01
J 2
(-4900 5225);
DISPLAY 0.723404 (-4900 5225);
PAINT GREEN (-4900 5225);
DISPLAY INVISIBLE (-4900 5225);
FORCEPROP 1 LAST MATERIAL X6S
J 2
(-4775 5200);
DISPLAY 0.723404 (-4775 5200);
PAINT GREEN (-4775 5200);
DISPLAY INVISIBLE (-4775 5200);
FORCEPROP 1 LAST PIN_NAMES_ROTATE True
J 2
(-4925 5150);
DISPLAY 0.489362 (-4925 5150);
PAINT GREEN (-4925 5150);
DISPLAY INVISIBLE (-4925 5150);
FORCEPROP 0 LAST PACK_TYPE C0201
J 2
(-5075 5150);
DISPLAY 0.680851 (-5075 5150);
DISPLAY INVISIBLE (-5075 5150);
FORCEADD Q_CAP_DIFFBUS..2
R 2
(-4925 5100);
FORCEPROP 1 LAST LOCATION C514
J 2
(-4725 5100);
DISPLAY 0.723404 (-4725 5100);
PAINT GREEN (-4725 5100);
FORCEPROP 0 LAST $SEC 1
J 0
(-4725 5150);
DISPLAY 0.680851 (-4725 5150);
PAINT MONO (-4725 5150);
DISPLAY INVISIBLE (-4725 5150);
FORCEPROP 0 LAST CDS_SEC 1
J 0
(-4725 5150);
DISPLAY 0.680851 (-4725 5150);
DISPLAY INVISIBLE (-4725 5150);
FORCEPROP 0 LASTPIN (-4850 5100) $PN 1
J 0
(-4840 5110);
DISPLAY 0.680851 (-4840 5110);
PAINT MONO (-4840 5110);
FORCEPROP 0 LASTPIN (-5000 5100) $PN 2
J 2
(-5010 5110);
DISPLAY 0.680851 (-5010 5110);
PAINT MONO (-5010 5110);
FORCEPROP 2 LAST VALUE DIFF BUS_0.22UF
J 2
(-5050 5100);
DISPLAY 0.553191 (-5050 5100);
FORCEPROP 1 LAST CDS_LMAN_SYM_OUTLINE -25,50,25,-50
J 2
(-4925 5100);
DISPLAY 0.468085 (-4925 5100);
PAINT GREEN (-4925 5100);
DISPLAY INVISIBLE (-4925 5100);
FORCEPROP 2 LAST CDS_LIB pure_quanta
J 0
(-4925 5100);
DISPLAY INVISIBLE (-4925 5100);
FORCEPROP 1 LAST PATH I48
J 2
(-4925 5100);
DISPLAY 0.723404 (-4925 5100);
DISPLAY INVISIBLE (-4925 5100);
FORCEPROP 0 LAST VOLTAGE 6.3V
J 2
(-5000 5275);
DISPLAY 0.680851 (-5000 5275);
DISPLAY INVISIBLE (-5000 5275);
FORCEPROP 0 LAST TOLERANCE 20%
J 2
(-5000 5225);
DISPLAY 0.680851 (-5000 5225);
DISPLAY INVISIBLE (-5000 5225);
FORCEPROP 1 LAST PART_NUMBER SP_CH4221MEE01
J 2
(-4900 5175);
DISPLAY 0.723404 (-4900 5175);
PAINT GREEN (-4900 5175);
DISPLAY INVISIBLE (-4900 5175);
FORCEPROP 1 LAST MATERIAL X6S
J 2
(-4775 5150);
DISPLAY 0.723404 (-4775 5150);
PAINT GREEN (-4775 5150);
DISPLAY INVISIBLE (-4775 5150);
FORCEPROP 1 LAST PIN_NAMES_ROTATE True
J 2
(-4925 5100);
DISPLAY 0.489362 (-4925 5100);
PAINT GREEN (-4925 5100);
DISPLAY INVISIBLE (-4925 5100);
FORCEPROP 0 LAST PACK_TYPE C0201
J 2
(-5075 5100);
DISPLAY 0.680851 (-5075 5100);
DISPLAY INVISIBLE (-5075 5100);
FORCEADD Q_CAP_DIFFBUS..2
R 2
(-4925 5200);
FORCEPROP 1 LAST LOCATION C512
J 2
(-4725 5200);
DISPLAY 0.723404 (-4725 5200);
PAINT GREEN (-4725 5200);
FORCEPROP 0 LAST $SEC 1
J 0
(-4725 5250);
DISPLAY 0.680851 (-4725 5250);
PAINT MONO (-4725 5250);
DISPLAY INVISIBLE (-4725 5250);
FORCEPROP 0 LAST CDS_SEC 1
J 0
(-4725 5250);
DISPLAY 0.680851 (-4725 5250);
DISPLAY INVISIBLE (-4725 5250);
FORCEPROP 0 LASTPIN (-4850 5200) $PN 1
J 0
(-4840 5210);
DISPLAY 0.680851 (-4840 5210);
PAINT MONO (-4840 5210);
FORCEPROP 0 LASTPIN (-5000 5200) $PN 2
J 2
(-5010 5210);
DISPLAY 0.680851 (-5010 5210);
PAINT MONO (-5010 5210);
FORCEPROP 2 LAST VALUE DIFF BUS_0.22UF
J 2
(-5050 5200);
DISPLAY 0.553191 (-5050 5200);
FORCEPROP 1 LAST CDS_LMAN_SYM_OUTLINE -25,50,25,-50
J 2
(-4925 5200);
DISPLAY 0.468085 (-4925 5200);
PAINT GREEN (-4925 5200);
DISPLAY INVISIBLE (-4925 5200);
FORCEPROP 2 LAST CDS_LIB pure_quanta
J 0
(-4925 5200);
DISPLAY INVISIBLE (-4925 5200);
FORCEPROP 1 LAST PATH I49
J 2
(-4925 5200);
DISPLAY 0.723404 (-4925 5200);
DISPLAY INVISIBLE (-4925 5200);
FORCEPROP 0 LAST VOLTAGE 6.3V
J 2
(-5000 5375);
DISPLAY 0.680851 (-5000 5375);
DISPLAY INVISIBLE (-5000 5375);
FORCEPROP 0 LAST TOLERANCE 20%
J 2
(-5000 5325);
DISPLAY 0.680851 (-5000 5325);
DISPLAY INVISIBLE (-5000 5325);
FORCEPROP 1 LAST PART_NUMBER SP_CH4221MEE01
J 2
(-4900 5275);
DISPLAY 0.723404 (-4900 5275);
PAINT GREEN (-4900 5275);
DISPLAY INVISIBLE (-4900 5275);
FORCEPROP 1 LAST MATERIAL X6S
J 2
(-4775 5250);
DISPLAY 0.723404 (-4775 5250);
PAINT GREEN (-4775 5250);
DISPLAY INVISIBLE (-4775 5250);
FORCEPROP 1 LAST PIN_NAMES_ROTATE True
J 2
(-4925 5200);
DISPLAY 0.489362 (-4925 5200);
PAINT GREEN (-4925 5200);
DISPLAY INVISIBLE (-4925 5200);
FORCEPROP 0 LAST PACK_TYPE C0201
J 2
(-5075 5200);
DISPLAY 0.680851 (-5075 5200);
DISPLAY INVISIBLE (-5075 5200);
FORCEADD TAP..6
(-5800 4450);
FORCEPROP 3 LASTPIN (-5750 4450) SIG_NAME P5E_CPU0_P0_TX_DN<13>
J 0
(-5740 4460);
DISPLAY 0.659574 (-5740 4460);
PAINT MONO (-5740 4460);
DISPLAY INVISIBLE (-5740 4460);
FORCEPROP 1 LASTPIN (-5750 4450) BN 13
J 0
(-5802 4458);
DISPLAY 0.680851 (-5802 4458);
PAINT MONO (-5802 4458);
FORCEPROP 2 LAST CDS_LIB standard
J 0
(-5800 4450);
DISPLAY INVISIBLE (-5800 4450);
FORCEPROP 1 LAST PATH I5
J 0
(-5802 4450);
DISPLAY 0.872340 (-5802 4450);
PAINT GREEN (-5802 4450);
DISPLAY INVISIBLE (-5802 4450);
FORCEPROP 1 LAST BODY_TYPE PLUMBING
J 0
(-5800 4400);
DISPLAY 0.574468 (-5800 4400);
PAINT GREEN (-5800 4400);
DISPLAY INVISIBLE (-5800 4400);
FORCEPROP 1 LAST HDL_TAP TRUE
J 0
(-5475 4325);
DISPLAY 0.574468 (-5475 4325);
PAINT GREEN (-5475 4325);
DISPLAY INVISIBLE (-5475 4325);
FORCEADD Q_CAP_DIFFBUS..2
R 2
(-4925 5250);
FORCEPROP 1 LAST LOCATION C511
J 2
(-4725 5250);
DISPLAY 0.723404 (-4725 5250);
PAINT GREEN (-4725 5250);
FORCEPROP 0 LAST $SEC 1
J 0
(-4725 5300);
DISPLAY 0.680851 (-4725 5300);
PAINT MONO (-4725 5300);
DISPLAY INVISIBLE (-4725 5300);
FORCEPROP 0 LAST CDS_SEC 1
J 0
(-4725 5300);
DISPLAY 0.680851 (-4725 5300);
DISPLAY INVISIBLE (-4725 5300);
FORCEPROP 0 LASTPIN (-4850 5250) $PN 1
J 0
(-4840 5260);
DISPLAY 0.680851 (-4840 5260);
PAINT MONO (-4840 5260);
FORCEPROP 0 LASTPIN (-5000 5250) $PN 2
J 2
(-5010 5260);
DISPLAY 0.680851 (-5010 5260);
PAINT MONO (-5010 5260);
FORCEPROP 2 LAST VALUE DIFF BUS_0.22UF
J 2
(-5050 5250);
DISPLAY 0.553191 (-5050 5250);
FORCEPROP 1 LAST CDS_LMAN_SYM_OUTLINE -25,50,25,-50
J 2
(-4925 5250);
DISPLAY 0.468085 (-4925 5250);
PAINT GREEN (-4925 5250);
DISPLAY INVISIBLE (-4925 5250);
FORCEPROP 2 LAST CDS_LIB pure_quanta
J 0
(-4925 5250);
DISPLAY INVISIBLE (-4925 5250);
FORCEPROP 1 LAST PATH I50
J 2
(-4925 5250);
DISPLAY 0.723404 (-4925 5250);
DISPLAY INVISIBLE (-4925 5250);
FORCEPROP 0 LAST VOLTAGE 6.3V
J 2
(-5000 5425);
DISPLAY 0.680851 (-5000 5425);
DISPLAY INVISIBLE (-5000 5425);
FORCEPROP 0 LAST TOLERANCE 20%
J 2
(-5000 5375);
DISPLAY 0.680851 (-5000 5375);
DISPLAY INVISIBLE (-5000 5375);
FORCEPROP 1 LAST PART_NUMBER SP_CH4221MEE01
J 2
(-4900 5325);
DISPLAY 0.723404 (-4900 5325);
PAINT GREEN (-4900 5325);
DISPLAY INVISIBLE (-4900 5325);
FORCEPROP 1 LAST MATERIAL X6S
J 2
(-4775 5300);
DISPLAY 0.723404 (-4775 5300);
PAINT GREEN (-4775 5300);
DISPLAY INVISIBLE (-4775 5300);
FORCEPROP 1 LAST PIN_NAMES_ROTATE True
J 2
(-4925 5250);
DISPLAY 0.489362 (-4925 5250);
PAINT GREEN (-4925 5250);
DISPLAY INVISIBLE (-4925 5250);
FORCEPROP 0 LAST PACK_TYPE C0201
J 2
(-5075 5250);
DISPLAY 0.680851 (-5075 5250);
DISPLAY INVISIBLE (-5075 5250);
FORCEADD Q_CAP_DIFFBUS..2
R 2
(-4925 5300);
FORCEPROP 1 LAST LOCATION C510
J 2
(-4725 5300);
DISPLAY 0.723404 (-4725 5300);
PAINT GREEN (-4725 5300);
FORCEPROP 0 LAST $SEC 1
J 0
(-4725 5350);
DISPLAY 0.680851 (-4725 5350);
PAINT MONO (-4725 5350);
DISPLAY INVISIBLE (-4725 5350);
FORCEPROP 0 LAST CDS_SEC 1
J 0
(-4725 5350);
DISPLAY 0.680851 (-4725 5350);
DISPLAY INVISIBLE (-4725 5350);
FORCEPROP 0 LASTPIN (-4850 5300) $PN 1
J 0
(-4840 5310);
DISPLAY 0.680851 (-4840 5310);
PAINT MONO (-4840 5310);
FORCEPROP 0 LASTPIN (-5000 5300) $PN 2
J 2
(-5010 5310);
DISPLAY 0.680851 (-5010 5310);
PAINT MONO (-5010 5310);
FORCEPROP 2 LAST VALUE DIFF BUS_0.22UF
J 2
(-5050 5300);
DISPLAY 0.553191 (-5050 5300);
FORCEPROP 1 LAST CDS_LMAN_SYM_OUTLINE -25,50,25,-50
J 2
(-4925 5300);
DISPLAY 0.468085 (-4925 5300);
PAINT GREEN (-4925 5300);
DISPLAY INVISIBLE (-4925 5300);
FORCEPROP 2 LAST CDS_LIB pure_quanta
J 0
(-4925 5300);
DISPLAY INVISIBLE (-4925 5300);
FORCEPROP 1 LAST PATH I51
J 2
(-4925 5300);
DISPLAY 0.723404 (-4925 5300);
DISPLAY INVISIBLE (-4925 5300);
FORCEPROP 0 LAST PACK_TYPE C0201
J 2
(-5075 5300);
DISPLAY 0.680851 (-5075 5300);
DISPLAY INVISIBLE (-5075 5300);
FORCEPROP 1 LAST PIN_NAMES_ROTATE True
J 2
(-4925 5300);
DISPLAY 0.489362 (-4925 5300);
PAINT GREEN (-4925 5300);
DISPLAY INVISIBLE (-4925 5300);
FORCEPROP 1 LAST MATERIAL X6S
J 2
(-4775 5350);
DISPLAY 0.723404 (-4775 5350);
PAINT GREEN (-4775 5350);
DISPLAY INVISIBLE (-4775 5350);
FORCEPROP 1 LAST PART_NUMBER SP_CH4221MEE01
J 2
(-4900 5375);
DISPLAY 0.723404 (-4900 5375);
PAINT GREEN (-4900 5375);
DISPLAY INVISIBLE (-4900 5375);
FORCEPROP 0 LAST TOLERANCE 20%
J 2
(-5000 5425);
DISPLAY 0.680851 (-5000 5425);
DISPLAY INVISIBLE (-5000 5425);
FORCEPROP 0 LAST VOLTAGE 6.3V
J 2
(-5000 5475);
DISPLAY 0.680851 (-5000 5475);
DISPLAY INVISIBLE (-5000 5475);
FORCEADD Q_CAP_DIFFBUS..2
R 2
(-4925 5350);
FORCEPROP 1 LAST LOCATION C542
J 2
(-4725 5350);
DISPLAY 0.723404 (-4725 5350);
PAINT GREEN (-4725 5350);
FORCEPROP 0 LAST $SEC 1
J 0
(-4725 5400);
DISPLAY 0.680851 (-4725 5400);
PAINT MONO (-4725 5400);
DISPLAY INVISIBLE (-4725 5400);
FORCEPROP 0 LAST CDS_SEC 1
J 0
(-4725 5400);
DISPLAY 0.680851 (-4725 5400);
DISPLAY INVISIBLE (-4725 5400);
FORCEPROP 0 LASTPIN (-4850 5350) $PN 1
J 0
(-4840 5360);
DISPLAY 0.680851 (-4840 5360);
PAINT MONO (-4840 5360);
FORCEPROP 0 LASTPIN (-5000 5350) $PN 2
J 2
(-5010 5360);
DISPLAY 0.680851 (-5010 5360);
PAINT MONO (-5010 5360);
FORCEPROP 2 LAST VALUE DIFF BUS_0.22UF
J 2
(-5050 5350);
DISPLAY 0.553191 (-5050 5350);
FORCEPROP 1 LAST CDS_LMAN_SYM_OUTLINE -25,50,25,-50
J 2
(-4925 5350);
DISPLAY 0.468085 (-4925 5350);
PAINT GREEN (-4925 5350);
DISPLAY INVISIBLE (-4925 5350);
FORCEPROP 2 LAST CDS_LIB pure_quanta
J 0
(-4925 5350);
DISPLAY INVISIBLE (-4925 5350);
FORCEPROP 1 LAST PATH I52
J 2
(-4925 5350);
DISPLAY 0.723404 (-4925 5350);
DISPLAY INVISIBLE (-4925 5350);
FORCEPROP 0 LAST VOLTAGE 6.3V
J 2
(-5000 5525);
DISPLAY 0.680851 (-5000 5525);
DISPLAY INVISIBLE (-5000 5525);
FORCEPROP 0 LAST TOLERANCE 20%
J 2
(-5000 5475);
DISPLAY 0.680851 (-5000 5475);
DISPLAY INVISIBLE (-5000 5475);
FORCEPROP 1 LAST PART_NUMBER SP_CH4221MEE01
J 2
(-4900 5425);
DISPLAY 0.723404 (-4900 5425);
PAINT GREEN (-4900 5425);
DISPLAY INVISIBLE (-4900 5425);
FORCEPROP 1 LAST MATERIAL X6S
J 2
(-4775 5400);
DISPLAY 0.723404 (-4775 5400);
PAINT GREEN (-4775 5400);
DISPLAY INVISIBLE (-4775 5400);
FORCEPROP 1 LAST PIN_NAMES_ROTATE True
J 2
(-4925 5350);
DISPLAY 0.489362 (-4925 5350);
PAINT GREEN (-4925 5350);
DISPLAY INVISIBLE (-4925 5350);
FORCEPROP 0 LAST PACK_TYPE C0201
J 2
(-5075 5350);
DISPLAY 0.680851 (-5075 5350);
DISPLAY INVISIBLE (-5075 5350);
FORCEADD Q_CAP_DIFFBUS..2
R 2
(-4925 5400);
FORCEPROP 1 LAST LOCATION C508
J 2
(-4725 5400);
DISPLAY 0.723404 (-4725 5400);
PAINT GREEN (-4725 5400);
FORCEPROP 0 LAST $SEC 1
J 0
(-4725 5450);
DISPLAY 0.680851 (-4725 5450);
PAINT MONO (-4725 5450);
DISPLAY INVISIBLE (-4725 5450);
FORCEPROP 0 LAST CDS_SEC 1
J 0
(-4725 5450);
DISPLAY 0.680851 (-4725 5450);
DISPLAY INVISIBLE (-4725 5450);
FORCEPROP 0 LASTPIN (-4850 5400) $PN 1
J 0
(-4840 5410);
DISPLAY 0.680851 (-4840 5410);
PAINT MONO (-4840 5410);
FORCEPROP 0 LASTPIN (-5000 5400) $PN 2
J 2
(-5010 5410);
DISPLAY 0.680851 (-5010 5410);
PAINT MONO (-5010 5410);
FORCEPROP 2 LAST VALUE DIFF BUS_0.22UF
J 2
(-5050 5400);
DISPLAY 0.553191 (-5050 5400);
FORCEPROP 1 LAST CDS_LMAN_SYM_OUTLINE -25,50,25,-50
J 2
(-4925 5400);
DISPLAY 0.468085 (-4925 5400);
PAINT GREEN (-4925 5400);
DISPLAY INVISIBLE (-4925 5400);
FORCEPROP 2 LAST CDS_LIB pure_quanta
J 0
(-4925 5400);
DISPLAY INVISIBLE (-4925 5400);
FORCEPROP 1 LAST PATH I53
J 2
(-4925 5400);
DISPLAY 0.723404 (-4925 5400);
DISPLAY INVISIBLE (-4925 5400);
FORCEPROP 0 LAST VOLTAGE 6.3V
J 2
(-5000 5575);
DISPLAY 0.680851 (-5000 5575);
DISPLAY INVISIBLE (-5000 5575);
FORCEPROP 0 LAST TOLERANCE 20%
J 2
(-5000 5525);
DISPLAY 0.680851 (-5000 5525);
DISPLAY INVISIBLE (-5000 5525);
FORCEPROP 1 LAST PART_NUMBER SP_CH4221MEE01
J 2
(-4900 5475);
DISPLAY 0.723404 (-4900 5475);
PAINT GREEN (-4900 5475);
DISPLAY INVISIBLE (-4900 5475);
FORCEPROP 1 LAST MATERIAL X6S
J 2
(-4775 5450);
DISPLAY 0.723404 (-4775 5450);
PAINT GREEN (-4775 5450);
DISPLAY INVISIBLE (-4775 5450);
FORCEPROP 1 LAST PIN_NAMES_ROTATE True
J 2
(-4925 5400);
DISPLAY 0.489362 (-4925 5400);
PAINT GREEN (-4925 5400);
DISPLAY INVISIBLE (-4925 5400);
FORCEPROP 0 LAST PACK_TYPE C0201
J 2
(-5075 5400);
DISPLAY 0.680851 (-5075 5400);
DISPLAY INVISIBLE (-5075 5400);
FORCEADD Q_CAP_DIFFBUS..2
R 2
(-4925 5450);
FORCEPROP 1 LAST LOCATION C507
J 2
(-4725 5450);
DISPLAY 0.723404 (-4725 5450);
PAINT GREEN (-4725 5450);
FORCEPROP 0 LAST $SEC 1
J 0
(-4725 5500);
DISPLAY 0.680851 (-4725 5500);
PAINT MONO (-4725 5500);
DISPLAY INVISIBLE (-4725 5500);
FORCEPROP 0 LAST CDS_SEC 1
J 0
(-4725 5500);
DISPLAY 0.680851 (-4725 5500);
DISPLAY INVISIBLE (-4725 5500);
FORCEPROP 0 LASTPIN (-4850 5450) $PN 1
J 0
(-4840 5460);
DISPLAY 0.680851 (-4840 5460);
PAINT MONO (-4840 5460);
FORCEPROP 0 LASTPIN (-5000 5450) $PN 2
J 2
(-5010 5460);
DISPLAY 0.680851 (-5010 5460);
PAINT MONO (-5010 5460);
FORCEPROP 2 LAST VALUE DIFF BUS_0.22UF
J 2
(-5050 5450);
DISPLAY 0.553191 (-5050 5450);
FORCEPROP 1 LAST CDS_LMAN_SYM_OUTLINE -25,50,25,-50
J 2
(-4925 5450);
DISPLAY 0.468085 (-4925 5450);
PAINT GREEN (-4925 5450);
DISPLAY INVISIBLE (-4925 5450);
FORCEPROP 2 LAST CDS_LIB pure_quanta
J 0
(-4925 5450);
DISPLAY INVISIBLE (-4925 5450);
FORCEPROP 1 LAST PATH I54
J 2
(-4925 5450);
DISPLAY 0.723404 (-4925 5450);
DISPLAY INVISIBLE (-4925 5450);
FORCEPROP 0 LAST PACK_TYPE C0201
J 2
(-5075 5450);
DISPLAY 0.680851 (-5075 5450);
DISPLAY INVISIBLE (-5075 5450);
FORCEPROP 1 LAST PIN_NAMES_ROTATE True
J 2
(-4925 5450);
DISPLAY 0.489362 (-4925 5450);
PAINT GREEN (-4925 5450);
DISPLAY INVISIBLE (-4925 5450);
FORCEPROP 1 LAST MATERIAL X6S
J 2
(-4775 5500);
DISPLAY 0.723404 (-4775 5500);
PAINT GREEN (-4775 5500);
DISPLAY INVISIBLE (-4775 5500);
FORCEPROP 1 LAST PART_NUMBER SP_CH4221MEE01
J 2
(-4900 5525);
DISPLAY 0.723404 (-4900 5525);
PAINT GREEN (-4900 5525);
DISPLAY INVISIBLE (-4900 5525);
FORCEPROP 0 LAST TOLERANCE 20%
J 2
(-5000 5575);
DISPLAY 0.680851 (-5000 5575);
DISPLAY INVISIBLE (-5000 5575);
FORCEPROP 0 LAST VOLTAGE 6.3V
J 2
(-5000 5625);
DISPLAY 0.680851 (-5000 5625);
DISPLAY INVISIBLE (-5000 5625);
FORCEADD Q_CAP_DIFFBUS..2
R 2
(-4925 5500);
FORCEPROP 1 LAST LOCATION C506
J 2
(-4725 5500);
DISPLAY 0.723404 (-4725 5500);
PAINT GREEN (-4725 5500);
FORCEPROP 0 LAST $SEC 1
J 0
(-4725 5550);
DISPLAY 0.680851 (-4725 5550);
PAINT MONO (-4725 5550);
DISPLAY INVISIBLE (-4725 5550);
FORCEPROP 0 LAST CDS_SEC 1
J 0
(-4725 5550);
DISPLAY 0.680851 (-4725 5550);
DISPLAY INVISIBLE (-4725 5550);
FORCEPROP 0 LASTPIN (-4850 5500) $PN 1
J 0
(-4840 5510);
DISPLAY 0.680851 (-4840 5510);
PAINT MONO (-4840 5510);
FORCEPROP 0 LASTPIN (-5000 5500) $PN 2
J 2
(-5010 5510);
DISPLAY 0.680851 (-5010 5510);
PAINT MONO (-5010 5510);
FORCEPROP 2 LAST VALUE DIFF BUS_0.22UF
J 2
(-5050 5500);
DISPLAY 0.553191 (-5050 5500);
FORCEPROP 1 LAST CDS_LMAN_SYM_OUTLINE -25,50,25,-50
J 2
(-4925 5500);
DISPLAY 0.468085 (-4925 5500);
PAINT GREEN (-4925 5500);
DISPLAY INVISIBLE (-4925 5500);
FORCEPROP 2 LAST CDS_LIB pure_quanta
J 0
(-4925 5500);
DISPLAY INVISIBLE (-4925 5500);
FORCEPROP 1 LAST PATH I55
J 2
(-4925 5500);
DISPLAY 0.723404 (-4925 5500);
DISPLAY INVISIBLE (-4925 5500);
FORCEPROP 0 LAST PACK_TYPE C0201
J 2
(-5075 5500);
DISPLAY 0.680851 (-5075 5500);
DISPLAY INVISIBLE (-5075 5500);
FORCEPROP 1 LAST PIN_NAMES_ROTATE True
J 2
(-4925 5500);
DISPLAY 0.489362 (-4925 5500);
PAINT GREEN (-4925 5500);
DISPLAY INVISIBLE (-4925 5500);
FORCEPROP 1 LAST MATERIAL X6S
J 2
(-4775 5550);
DISPLAY 0.723404 (-4775 5550);
PAINT GREEN (-4775 5550);
DISPLAY INVISIBLE (-4775 5550);
FORCEPROP 1 LAST PART_NUMBER SP_CH4221MEE01
J 2
(-4900 5575);
DISPLAY 0.723404 (-4900 5575);
PAINT GREEN (-4900 5575);
DISPLAY INVISIBLE (-4900 5575);
FORCEPROP 0 LAST TOLERANCE 20%
J 2
(-5000 5625);
DISPLAY 0.680851 (-5000 5625);
DISPLAY INVISIBLE (-5000 5625);
FORCEPROP 0 LAST VOLTAGE 6.3V
J 2
(-5000 5675);
DISPLAY 0.680851 (-5000 5675);
DISPLAY INVISIBLE (-5000 5675);
FORCEADD Q_CAP_DIFFBUS..2
R 2
(-4925 5550);
FORCEPROP 1 LAST LOCATION C505
J 2
(-4675 5550);
DISPLAY 0.723404 (-4675 5550);
PAINT GREEN (-4675 5550);
FORCEPROP 0 LAST $SEC 1
J 0
(-4675 5600);
DISPLAY 0.680851 (-4675 5600);
PAINT MONO (-4675 5600);
DISPLAY INVISIBLE (-4675 5600);
FORCEPROP 0 LAST CDS_SEC 1
J 0
(-4675 5600);
DISPLAY 0.680851 (-4675 5600);
DISPLAY INVISIBLE (-4675 5600);
FORCEPROP 0 LASTPIN (-4850 5550) $PN 1
J 0
(-4840 5560);
DISPLAY 0.680851 (-4840 5560);
PAINT MONO (-4840 5560);
FORCEPROP 0 LASTPIN (-5000 5550) $PN 2
J 2
(-5010 5560);
DISPLAY 0.680851 (-5010 5560);
PAINT MONO (-5010 5560);
FORCEPROP 2 LAST VALUE DIFF BUS_0.22UF
J 2
(-5050 5550);
DISPLAY 0.553191 (-5050 5550);
FORCEPROP 1 LAST CDS_LMAN_SYM_OUTLINE -25,50,25,-50
J 2
(-4925 5550);
DISPLAY 0.468085 (-4925 5550);
PAINT GREEN (-4925 5550);
DISPLAY INVISIBLE (-4925 5550);
FORCEPROP 2 LAST CDS_LIB pure_quanta
J 0
(-4925 5550);
DISPLAY INVISIBLE (-4925 5550);
FORCEPROP 1 LAST PATH I56
J 2
(-4925 5550);
DISPLAY 0.723404 (-4925 5550);
DISPLAY INVISIBLE (-4925 5550);
FORCEPROP 0 LAST PACK_TYPE C0201
J 2
(-5075 5550);
DISPLAY 0.680851 (-5075 5550);
DISPLAY INVISIBLE (-5075 5550);
FORCEPROP 1 LAST PIN_NAMES_ROTATE True
J 2
(-4925 5550);
DISPLAY 0.489362 (-4925 5550);
PAINT GREEN (-4925 5550);
DISPLAY INVISIBLE (-4925 5550);
FORCEPROP 1 LAST MATERIAL X6S
J 2
(-4775 5600);
DISPLAY 0.723404 (-4775 5600);
PAINT GREEN (-4775 5600);
DISPLAY INVISIBLE (-4775 5600);
FORCEPROP 1 LAST PART_NUMBER SP_CH4221MEE01
J 2
(-4900 5625);
DISPLAY 0.723404 (-4900 5625);
PAINT GREEN (-4900 5625);
DISPLAY INVISIBLE (-4900 5625);
FORCEPROP 0 LAST TOLERANCE 20%
J 2
(-5000 5675);
DISPLAY 0.680851 (-5000 5675);
DISPLAY INVISIBLE (-5000 5675);
FORCEPROP 0 LAST VOLTAGE 6.3V
J 2
(-5000 5725);
DISPLAY 0.680851 (-5000 5725);
DISPLAY INVISIBLE (-5000 5725);
FORCEADD Q_CAP_DIFFBUS..2
R 2
(-4925 5600);
FORCEPROP 1 LAST LOCATION C504
J 2
(-4675 5600);
DISPLAY 0.723404 (-4675 5600);
PAINT GREEN (-4675 5600);
FORCEPROP 0 LAST $SEC 1
J 0
(-4675 5650);
DISPLAY 0.680851 (-4675 5650);
PAINT MONO (-4675 5650);
DISPLAY INVISIBLE (-4675 5650);
FORCEPROP 0 LAST CDS_SEC 1
J 0
(-4675 5650);
DISPLAY 0.680851 (-4675 5650);
DISPLAY INVISIBLE (-4675 5650);
FORCEPROP 0 LASTPIN (-4850 5600) $PN 1
J 0
(-4840 5610);
DISPLAY 0.680851 (-4840 5610);
PAINT MONO (-4840 5610);
FORCEPROP 0 LASTPIN (-5000 5600) $PN 2
J 2
(-5010 5610);
DISPLAY 0.680851 (-5010 5610);
PAINT MONO (-5010 5610);
FORCEPROP 2 LAST VALUE DIFF BUS_0.22UF
J 2
(-5050 5600);
DISPLAY 0.553191 (-5050 5600);
FORCEPROP 1 LAST CDS_LMAN_SYM_OUTLINE -25,50,25,-50
J 2
(-4925 5600);
DISPLAY 0.468085 (-4925 5600);
PAINT GREEN (-4925 5600);
DISPLAY INVISIBLE (-4925 5600);
FORCEPROP 2 LAST CDS_LIB pure_quanta
J 0
(-4925 5600);
DISPLAY INVISIBLE (-4925 5600);
FORCEPROP 1 LAST PATH I57
J 2
(-4925 5600);
DISPLAY 0.723404 (-4925 5600);
DISPLAY INVISIBLE (-4925 5600);
FORCEPROP 0 LAST VOLTAGE 6.3V
J 2
(-5000 5775);
DISPLAY 0.680851 (-5000 5775);
DISPLAY INVISIBLE (-5000 5775);
FORCEPROP 0 LAST TOLERANCE 20%
J 2
(-5000 5725);
DISPLAY 0.680851 (-5000 5725);
DISPLAY INVISIBLE (-5000 5725);
FORCEPROP 1 LAST PART_NUMBER SP_CH4221MEE01
J 2
(-4900 5675);
DISPLAY 0.723404 (-4900 5675);
PAINT GREEN (-4900 5675);
DISPLAY INVISIBLE (-4900 5675);
FORCEPROP 1 LAST MATERIAL X6S
J 2
(-4775 5650);
DISPLAY 0.723404 (-4775 5650);
PAINT GREEN (-4775 5650);
DISPLAY INVISIBLE (-4775 5650);
FORCEPROP 1 LAST PIN_NAMES_ROTATE True
J 2
(-4925 5600);
DISPLAY 0.489362 (-4925 5600);
PAINT GREEN (-4925 5600);
DISPLAY INVISIBLE (-4925 5600);
FORCEPROP 0 LAST PACK_TYPE C0201
J 2
(-5075 5600);
DISPLAY 0.680851 (-5075 5600);
DISPLAY INVISIBLE (-5075 5600);
FORCEADD Q_CAP_DIFFBUS..2
R 2
(-4925 5650);
FORCEPROP 1 LAST LOCATION C503
J 2
(-4675 5650);
DISPLAY 0.723404 (-4675 5650);
PAINT GREEN (-4675 5650);
FORCEPROP 0 LAST $SEC 1
J 0
(-4675 5700);
DISPLAY 0.680851 (-4675 5700);
PAINT MONO (-4675 5700);
DISPLAY INVISIBLE (-4675 5700);
FORCEPROP 0 LAST CDS_SEC 1
J 0
(-4675 5700);
DISPLAY 0.680851 (-4675 5700);
DISPLAY INVISIBLE (-4675 5700);
FORCEPROP 0 LASTPIN (-4850 5650) $PN 1
J 0
(-4840 5660);
DISPLAY 0.680851 (-4840 5660);
PAINT MONO (-4840 5660);
FORCEPROP 0 LASTPIN (-5000 5650) $PN 2
J 2
(-5010 5660);
DISPLAY 0.680851 (-5010 5660);
PAINT MONO (-5010 5660);
FORCEPROP 2 LAST VALUE DIFF BUS_0.22UF
J 2
(-5050 5650);
DISPLAY 0.553191 (-5050 5650);
FORCEPROP 1 LAST CDS_LMAN_SYM_OUTLINE -25,50,25,-50
J 2
(-4925 5650);
DISPLAY 0.468085 (-4925 5650);
PAINT GREEN (-4925 5650);
DISPLAY INVISIBLE (-4925 5650);
FORCEPROP 2 LAST CDS_LIB pure_quanta
J 0
(-4925 5650);
DISPLAY INVISIBLE (-4925 5650);
FORCEPROP 1 LAST PATH I58
J 2
(-4925 5650);
DISPLAY 0.723404 (-4925 5650);
DISPLAY INVISIBLE (-4925 5650);
FORCEPROP 0 LAST PACK_TYPE C0201
J 2
(-5075 5650);
DISPLAY 0.680851 (-5075 5650);
DISPLAY INVISIBLE (-5075 5650);
FORCEPROP 1 LAST PIN_NAMES_ROTATE True
J 2
(-4925 5650);
DISPLAY 0.489362 (-4925 5650);
PAINT GREEN (-4925 5650);
DISPLAY INVISIBLE (-4925 5650);
FORCEPROP 1 LAST MATERIAL X6S
J 2
(-4775 5700);
DISPLAY 0.723404 (-4775 5700);
PAINT GREEN (-4775 5700);
DISPLAY INVISIBLE (-4775 5700);
FORCEPROP 1 LAST PART_NUMBER SP_CH4221MEE01
J 2
(-4900 5725);
DISPLAY 0.723404 (-4900 5725);
PAINT GREEN (-4900 5725);
DISPLAY INVISIBLE (-4900 5725);
FORCEPROP 0 LAST TOLERANCE 20%
J 2
(-5000 5775);
DISPLAY 0.680851 (-5000 5775);
DISPLAY INVISIBLE (-5000 5775);
FORCEPROP 0 LAST VOLTAGE 6.3V
J 2
(-5000 5825);
DISPLAY 0.680851 (-5000 5825);
DISPLAY INVISIBLE (-5000 5825);
FORCEADD Q_CAP_DIFFBUS..2
R 2
(-4925 5700);
FORCEPROP 1 LAST LOCATION C502
J 2
(-4675 5700);
DISPLAY 0.723404 (-4675 5700);
PAINT GREEN (-4675 5700);
FORCEPROP 0 LAST $SEC 1
J 0
(-4675 5750);
DISPLAY 0.680851 (-4675 5750);
PAINT MONO (-4675 5750);
DISPLAY INVISIBLE (-4675 5750);
FORCEPROP 0 LAST CDS_SEC 1
J 0
(-4675 5750);
DISPLAY 0.680851 (-4675 5750);
DISPLAY INVISIBLE (-4675 5750);
FORCEPROP 0 LASTPIN (-4850 5700) $PN 1
J 0
(-4840 5710);
DISPLAY 0.680851 (-4840 5710);
PAINT MONO (-4840 5710);
FORCEPROP 0 LASTPIN (-5000 5700) $PN 2
J 2
(-5010 5710);
DISPLAY 0.680851 (-5010 5710);
PAINT MONO (-5010 5710);
FORCEPROP 2 LAST VALUE DIFF BUS_0.22UF
J 2
(-5050 5700);
DISPLAY 0.553191 (-5050 5700);
FORCEPROP 1 LAST CDS_LMAN_SYM_OUTLINE -25,50,25,-50
J 2
(-4925 5700);
DISPLAY 0.468085 (-4925 5700);
PAINT GREEN (-4925 5700);
DISPLAY INVISIBLE (-4925 5700);
FORCEPROP 2 LAST CDS_LIB pure_quanta
J 0
(-4925 5700);
DISPLAY INVISIBLE (-4925 5700);
FORCEPROP 1 LAST PATH I59
J 2
(-4925 5700);
DISPLAY 0.723404 (-4925 5700);
DISPLAY INVISIBLE (-4925 5700);
FORCEPROP 0 LAST PACK_TYPE C0201
J 2
(-5075 5700);
DISPLAY 0.680851 (-5075 5700);
DISPLAY INVISIBLE (-5075 5700);
FORCEPROP 1 LAST PIN_NAMES_ROTATE True
J 2
(-4925 5700);
DISPLAY 0.489362 (-4925 5700);
PAINT GREEN (-4925 5700);
DISPLAY INVISIBLE (-4925 5700);
FORCEPROP 1 LAST MATERIAL X6S
J 2
(-4775 5750);
DISPLAY 0.723404 (-4775 5750);
PAINT GREEN (-4775 5750);
DISPLAY INVISIBLE (-4775 5750);
FORCEPROP 1 LAST PART_NUMBER SP_CH4221MEE01
J 2
(-4900 5775);
DISPLAY 0.723404 (-4900 5775);
PAINT GREEN (-4900 5775);
DISPLAY INVISIBLE (-4900 5775);
FORCEPROP 0 LAST TOLERANCE 20%
J 2
(-5000 5825);
DISPLAY 0.680851 (-5000 5825);
DISPLAY INVISIBLE (-5000 5825);
FORCEPROP 0 LAST VOLTAGE 6.3V
J 2
(-5000 5875);
DISPLAY 0.680851 (-5000 5875);
DISPLAY INVISIBLE (-5000 5875);
FORCEADD TAP..6
(-5800 4650);
FORCEPROP 3 LASTPIN (-5750 4650) SIG_NAME P5E_CPU0_P0_TX_DN<11>
J 0
(-5740 4660);
DISPLAY 0.659574 (-5740 4660);
PAINT MONO (-5740 4660);
DISPLAY INVISIBLE (-5740 4660);
FORCEPROP 1 LASTPIN (-5750 4650) BN 11
J 0
(-5802 4658);
DISPLAY 0.680851 (-5802 4658);
PAINT MONO (-5802 4658);
FORCEPROP 2 LAST CDS_LIB standard
J 0
(-5800 4650);
DISPLAY INVISIBLE (-5800 4650);
FORCEPROP 1 LAST PATH I6
J 0
(-5802 4650);
DISPLAY 0.872340 (-5802 4650);
PAINT GREEN (-5802 4650);
DISPLAY INVISIBLE (-5802 4650);
FORCEPROP 1 LAST BODY_TYPE PLUMBING
J 0
(-5800 4600);
DISPLAY 0.574468 (-5800 4600);
PAINT GREEN (-5800 4600);
DISPLAY INVISIBLE (-5800 4600);
FORCEPROP 1 LAST HDL_TAP TRUE
J 0
(-5475 4525);
DISPLAY 0.574468 (-5475 4525);
PAINT GREEN (-5475 4525);
DISPLAY INVISIBLE (-5475 4525);
FORCEADD Q_CAP_DIFFBUS..2
R 2
(-4925 5750);
FORCEPROP 1 LAST LOCATION C501
J 2
(-4675 5750);
DISPLAY 0.723404 (-4675 5750);
PAINT GREEN (-4675 5750);
FORCEPROP 0 LAST $SEC 1
J 0
(-4675 5800);
DISPLAY 0.680851 (-4675 5800);
PAINT MONO (-4675 5800);
DISPLAY INVISIBLE (-4675 5800);
FORCEPROP 0 LAST CDS_SEC 1
J 0
(-4675 5800);
DISPLAY 0.680851 (-4675 5800);
DISPLAY INVISIBLE (-4675 5800);
FORCEPROP 0 LASTPIN (-4850 5750) $PN 1
J 0
(-4840 5760);
DISPLAY 0.680851 (-4840 5760);
PAINT MONO (-4840 5760);
FORCEPROP 0 LASTPIN (-5000 5750) $PN 2
J 2
(-5010 5760);
DISPLAY 0.680851 (-5010 5760);
PAINT MONO (-5010 5760);
FORCEPROP 2 LAST VALUE DIFF BUS_0.22UF
J 2
(-5050 5750);
DISPLAY 0.553191 (-5050 5750);
FORCEPROP 1 LAST CDS_LMAN_SYM_OUTLINE -25,50,25,-50
J 2
(-4925 5750);
DISPLAY 0.468085 (-4925 5750);
PAINT GREEN (-4925 5750);
DISPLAY INVISIBLE (-4925 5750);
FORCEPROP 2 LAST CDS_LIB pure_quanta
J 0
(-4925 5750);
DISPLAY INVISIBLE (-4925 5750);
FORCEPROP 1 LAST PATH I60
J 2
(-4925 5750);
DISPLAY 0.723404 (-4925 5750);
DISPLAY INVISIBLE (-4925 5750);
FORCEPROP 0 LAST PACK_TYPE C0201
J 2
(-5075 5750);
DISPLAY 0.680851 (-5075 5750);
DISPLAY INVISIBLE (-5075 5750);
FORCEPROP 1 LAST PIN_NAMES_ROTATE True
J 2
(-4925 5750);
DISPLAY 0.489362 (-4925 5750);
PAINT GREEN (-4925 5750);
DISPLAY INVISIBLE (-4925 5750);
FORCEPROP 1 LAST MATERIAL X6S
J 2
(-4775 5800);
DISPLAY 0.723404 (-4775 5800);
PAINT GREEN (-4775 5800);
DISPLAY INVISIBLE (-4775 5800);
FORCEPROP 1 LAST PART_NUMBER SP_CH4221MEE01
J 2
(-4900 5825);
DISPLAY 0.723404 (-4900 5825);
PAINT GREEN (-4900 5825);
DISPLAY INVISIBLE (-4900 5825);
FORCEPROP 0 LAST TOLERANCE 20%
J 2
(-5000 5875);
DISPLAY 0.680851 (-5000 5875);
DISPLAY INVISIBLE (-5000 5875);
FORCEPROP 0 LAST VOLTAGE 6.3V
J 2
(-5000 5925);
DISPLAY 0.680851 (-5000 5925);
DISPLAY INVISIBLE (-5000 5925);
FORCEADD Q_CAP_DIFFBUS..2
(-4925 5800);
FORCEPROP 1 LAST LOCATION C500
J 0
(-4775 5800);
DISPLAY 0.723404 (-4775 5800);
PAINT GREEN (-4775 5800);
FORCEPROP 0 LAST $SEC 1
J 0
(-5125 5950);
DISPLAY 0.680851 (-5125 5950);
PAINT MONO (-5125 5950);
DISPLAY INVISIBLE (-5125 5950);
FORCEPROP 0 LAST CDS_SEC 1
J 0
(-5125 5950);
DISPLAY 0.680851 (-5125 5950);
DISPLAY INVISIBLE (-5125 5950);
FORCEPROP 0 LASTPIN (-5000 5800) $PN 1
J 2
(-5010 5810);
DISPLAY 0.680851 (-5010 5810);
PAINT MONO (-5010 5810);
FORCEPROP 0 LASTPIN (-4850 5800) $PN 2
J 0
(-4840 5810);
DISPLAY 0.680851 (-4840 5810);
PAINT MONO (-4840 5810);
FORCEPROP 2 LAST VALUE DIFF BUS_0.22UF
J 0
(-5500 5800);
DISPLAY 0.680851 (-5500 5800);
FORCEPROP 1 LAST PART_NUMBER SP_CH4221MEE01
J 0
(-5125 5900);
DISPLAY 0.723404 (-5125 5900);
PAINT GREEN (-5125 5900);
FORCEPROP 2 LAST PACK_TYPE C0201
J 0
(-5150 5850);
DISPLAY 0.680851 (-5150 5850);
FORCEPROP 1 LAST MATERIAL X6S
J 0
(-4975 5850);
DISPLAY 0.723404 (-4975 5850);
PAINT GREEN (-4975 5850);
FORCEPROP 2 LAST VOLTAGE 6.3V
J 0
(-4725 5850);
DISPLAY 0.680851 (-4725 5850);
FORCEPROP 2 LAST TOLERANCE 20%
J 0
(-4850 5850);
DISPLAY 0.680851 (-4850 5850);
FORCEPROP 1 LAST CDS_LMAN_SYM_OUTLINE -25,50,25,-50
J 0
(-4925 5800);
DISPLAY 0.468085 (-4925 5800);
PAINT GREEN (-4925 5800);
DISPLAY INVISIBLE (-4925 5800);
FORCEPROP 2 LAST CDS_LIB pure_quanta
J 0
(-4925 5800);
DISPLAY INVISIBLE (-4925 5800);
FORCEPROP 1 LAST PATH I61
J 0
(-4925 5800);
DISPLAY 0.723404 (-4925 5800);
DISPLAY INVISIBLE (-4925 5800);
FORCEPROP 1 LAST PIN_NAMES_ROTATE True
J 0
(-4925 5800);
DISPLAY 0.489362 (-4925 5800);
PAINT GREEN (-4925 5800);
DISPLAY INVISIBLE (-4925 5800);
FORCEADD TAP..6
R 2
(-3925 4300);
FORCEPROP 3 LASTPIN (-3975 4300) SIG_NAME P5E_CPU0_P0_TX_C_DP<15>
J 0
(-3965 4310);
DISPLAY 0.659574 (-3965 4310);
PAINT MONO (-3965 4310);
DISPLAY INVISIBLE (-3965 4310);
FORCEPROP 1 LASTPIN (-3975 4300) BN 15
J 2
(-3923 4308);
DISPLAY 0.680851 (-3923 4308);
PAINT MONO (-3923 4308);
FORCEPROP 2 LAST CDS_LIB standard
J 0
(-3925 4300);
DISPLAY INVISIBLE (-3925 4300);
FORCEPROP 1 LAST PATH I62
J 2
(-3923 4300);
DISPLAY 0.872340 (-3923 4300);
PAINT GREEN (-3923 4300);
DISPLAY INVISIBLE (-3923 4300);
FORCEPROP 2 LAST ROOM RISER1
J 0
(-4425 4350);
DISPLAY 0.829787 (-4425 4350);
PAINT RED (-4425 4350);
DISPLAY INVISIBLE (-4425 4350);
FORCEPROP 1 LAST HDL_TAP TRUE
J 2
(-4250 4175);
DISPLAY 0.702128 (-4250 4175);
PAINT GREEN (-4250 4175);
DISPLAY INVISIBLE (-4250 4175);
FORCEPROP 1 LAST BODY_TYPE PLUMBING
J 2
(-3925 4250);
DISPLAY 0.702128 (-3925 4250);
PAINT GREEN (-3925 4250);
DISPLAY INVISIBLE (-3925 4250);
FORCEPROP 2 LAST BOM_COST IO_SLOT
J 0
(-4425 4400);
DISPLAY 0.829787 (-4425 4400);
DISPLAY INVISIBLE (-4425 4400);
FORCEADD TAP..6
R 2
(-3925 4400);
FORCEPROP 3 LASTPIN (-3975 4400) SIG_NAME P5E_CPU0_P0_TX_C_DP<14>
J 0
(-3965 4410);
DISPLAY 0.659574 (-3965 4410);
PAINT MONO (-3965 4410);
DISPLAY INVISIBLE (-3965 4410);
FORCEPROP 1 LASTPIN (-3975 4400) BN 14
J 2
(-3923 4408);
DISPLAY 0.680851 (-3923 4408);
PAINT MONO (-3923 4408);
FORCEPROP 2 LAST CDS_LIB standard
J 0
(-3925 4400);
DISPLAY INVISIBLE (-3925 4400);
FORCEPROP 1 LAST PATH I63
J 2
(-3923 4400);
DISPLAY 0.872340 (-3923 4400);
PAINT GREEN (-3923 4400);
DISPLAY INVISIBLE (-3923 4400);
FORCEPROP 2 LAST ROOM RISER1
J 0
(-4425 4450);
DISPLAY 0.829787 (-4425 4450);
PAINT RED (-4425 4450);
DISPLAY INVISIBLE (-4425 4450);
FORCEPROP 1 LAST HDL_TAP TRUE
J 2
(-4250 4275);
DISPLAY 0.702128 (-4250 4275);
PAINT GREEN (-4250 4275);
DISPLAY INVISIBLE (-4250 4275);
FORCEPROP 1 LAST BODY_TYPE PLUMBING
J 2
(-3925 4350);
DISPLAY 0.702128 (-3925 4350);
PAINT GREEN (-3925 4350);
DISPLAY INVISIBLE (-3925 4350);
FORCEPROP 2 LAST BOM_COST IO_SLOT
J 0
(-4425 4500);
DISPLAY 0.829787 (-4425 4500);
DISPLAY INVISIBLE (-4425 4500);
FORCEADD TAP..6
R 2
(-3775 4350);
FORCEPROP 3 LASTPIN (-3825 4350) SIG_NAME P5E_CPU0_P0_TX_C_DN<14>
J 0
(-3815 4360);
DISPLAY 0.659574 (-3815 4360);
PAINT MONO (-3815 4360);
DISPLAY INVISIBLE (-3815 4360);
FORCEPROP 1 LASTPIN (-3825 4350) BN 14
J 2
(-3773 4358);
DISPLAY 0.680851 (-3773 4358);
PAINT MONO (-3773 4358);
FORCEPROP 2 LAST CDS_LIB standard
J 0
(-3775 4350);
DISPLAY INVISIBLE (-3775 4350);
FORCEPROP 1 LAST PATH I64
J 2
(-3773 4350);
DISPLAY 0.872340 (-3773 4350);
PAINT GREEN (-3773 4350);
DISPLAY INVISIBLE (-3773 4350);
FORCEPROP 2 LAST ROOM RISER1
J 0
(-4275 4400);
DISPLAY 0.829787 (-4275 4400);
PAINT RED (-4275 4400);
DISPLAY INVISIBLE (-4275 4400);
FORCEPROP 1 LAST HDL_TAP TRUE
J 2
(-4100 4225);
DISPLAY 0.702128 (-4100 4225);
PAINT GREEN (-4100 4225);
DISPLAY INVISIBLE (-4100 4225);
FORCEPROP 1 LAST BODY_TYPE PLUMBING
J 2
(-3775 4300);
DISPLAY 0.702128 (-3775 4300);
PAINT GREEN (-3775 4300);
DISPLAY INVISIBLE (-3775 4300);
FORCEPROP 2 LAST BOM_COST IO_SLOT
J 0
(-4275 4450);
DISPLAY 0.829787 (-4275 4450);
DISPLAY INVISIBLE (-4275 4450);
FORCEADD TAP..6
R 2
(-3775 4250);
FORCEPROP 3 LASTPIN (-3825 4250) SIG_NAME P5E_CPU0_P0_TX_C_DN<15>
J 0
(-3815 4260);
DISPLAY 0.659574 (-3815 4260);
PAINT MONO (-3815 4260);
DISPLAY INVISIBLE (-3815 4260);
FORCEPROP 1 LASTPIN (-3825 4250) BN 15
J 2
(-3773 4258);
DISPLAY 0.680851 (-3773 4258);
PAINT MONO (-3773 4258);
FORCEPROP 2 LAST CDS_LIB standard
J 0
(-3775 4250);
DISPLAY INVISIBLE (-3775 4250);
FORCEPROP 1 LAST PATH I65
J 2
(-3773 4250);
DISPLAY 0.872340 (-3773 4250);
PAINT GREEN (-3773 4250);
DISPLAY INVISIBLE (-3773 4250);
FORCEPROP 2 LAST ROOM RISER1
J 0
(-4275 4300);
DISPLAY 0.829787 (-4275 4300);
PAINT RED (-4275 4300);
DISPLAY INVISIBLE (-4275 4300);
FORCEPROP 1 LAST HDL_TAP TRUE
J 2
(-4100 4125);
DISPLAY 0.702128 (-4100 4125);
PAINT GREEN (-4100 4125);
DISPLAY INVISIBLE (-4100 4125);
FORCEPROP 1 LAST BODY_TYPE PLUMBING
J 2
(-3775 4200);
DISPLAY 0.702128 (-3775 4200);
PAINT GREEN (-3775 4200);
DISPLAY INVISIBLE (-3775 4200);
FORCEPROP 2 LAST BOM_COST IO_SLOT
J 0
(-4275 4350);
DISPLAY 0.829787 (-4275 4350);
DISPLAY INVISIBLE (-4275 4350);
FORCEADD TAP..6
R 2
(-3925 4500);
FORCEPROP 3 LASTPIN (-3975 4500) SIG_NAME P5E_CPU0_P0_TX_C_DP<13>
J 0
(-3965 4510);
DISPLAY 0.659574 (-3965 4510);
PAINT MONO (-3965 4510);
DISPLAY INVISIBLE (-3965 4510);
FORCEPROP 1 LASTPIN (-3975 4500) BN 13
J 2
(-3923 4508);
DISPLAY 0.680851 (-3923 4508);
PAINT MONO (-3923 4508);
FORCEPROP 2 LAST CDS_LIB standard
J 0
(-3925 4500);
DISPLAY INVISIBLE (-3925 4500);
FORCEPROP 1 LAST PATH I66
J 2
(-3923 4500);
DISPLAY 0.872340 (-3923 4500);
PAINT GREEN (-3923 4500);
DISPLAY INVISIBLE (-3923 4500);
FORCEPROP 2 LAST ROOM RISER1
J 0
(-4425 4550);
DISPLAY 0.829787 (-4425 4550);
PAINT RED (-4425 4550);
DISPLAY INVISIBLE (-4425 4550);
FORCEPROP 1 LAST HDL_TAP TRUE
J 2
(-4250 4375);
DISPLAY 0.702128 (-4250 4375);
PAINT GREEN (-4250 4375);
DISPLAY INVISIBLE (-4250 4375);
FORCEPROP 1 LAST BODY_TYPE PLUMBING
J 2
(-3925 4450);
DISPLAY 0.702128 (-3925 4450);
PAINT GREEN (-3925 4450);
DISPLAY INVISIBLE (-3925 4450);
FORCEPROP 2 LAST BOM_COST IO_SLOT
J 0
(-4425 4600);
DISPLAY 0.829787 (-4425 4600);
DISPLAY INVISIBLE (-4425 4600);
FORCEADD TAP..6
R 2
(-3925 4600);
FORCEPROP 3 LASTPIN (-3975 4600) SIG_NAME P5E_CPU0_P0_TX_C_DP<12>
J 0
(-3965 4610);
DISPLAY 0.659574 (-3965 4610);
PAINT MONO (-3965 4610);
DISPLAY INVISIBLE (-3965 4610);
FORCEPROP 1 LASTPIN (-3975 4600) BN 12
J 2
(-3923 4608);
DISPLAY 0.680851 (-3923 4608);
PAINT MONO (-3923 4608);
FORCEPROP 2 LAST CDS_LIB standard
J 0
(-3925 4600);
DISPLAY INVISIBLE (-3925 4600);
FORCEPROP 1 LAST PATH I67
J 2
(-3923 4600);
DISPLAY 0.872340 (-3923 4600);
PAINT GREEN (-3923 4600);
DISPLAY INVISIBLE (-3923 4600);
FORCEPROP 2 LAST ROOM RISER1
J 0
(-4425 4650);
DISPLAY 0.829787 (-4425 4650);
PAINT RED (-4425 4650);
DISPLAY INVISIBLE (-4425 4650);
FORCEPROP 1 LAST HDL_TAP TRUE
J 2
(-4250 4475);
DISPLAY 0.702128 (-4250 4475);
PAINT GREEN (-4250 4475);
DISPLAY INVISIBLE (-4250 4475);
FORCEPROP 1 LAST BODY_TYPE PLUMBING
J 2
(-3925 4550);
DISPLAY 0.702128 (-3925 4550);
PAINT GREEN (-3925 4550);
DISPLAY INVISIBLE (-3925 4550);
FORCEPROP 2 LAST BOM_COST IO_SLOT
J 0
(-4425 4700);
DISPLAY 0.829787 (-4425 4700);
DISPLAY INVISIBLE (-4425 4700);
FORCEADD TAP..6
R 2
(-3775 4550);
FORCEPROP 3 LASTPIN (-3825 4550) SIG_NAME P5E_CPU0_P0_TX_C_DN<12>
J 0
(-3815 4560);
DISPLAY 0.659574 (-3815 4560);
PAINT MONO (-3815 4560);
DISPLAY INVISIBLE (-3815 4560);
FORCEPROP 1 LASTPIN (-3825 4550) BN 12
J 2
(-3773 4558);
DISPLAY 0.680851 (-3773 4558);
PAINT MONO (-3773 4558);
FORCEPROP 2 LAST CDS_LIB standard
J 0
(-3775 4550);
DISPLAY INVISIBLE (-3775 4550);
FORCEPROP 1 LAST PATH I68
J 2
(-3773 4550);
DISPLAY 0.872340 (-3773 4550);
PAINT GREEN (-3773 4550);
DISPLAY INVISIBLE (-3773 4550);
FORCEPROP 2 LAST ROOM RISER1
J 0
(-4275 4600);
DISPLAY 0.829787 (-4275 4600);
PAINT RED (-4275 4600);
DISPLAY INVISIBLE (-4275 4600);
FORCEPROP 1 LAST HDL_TAP TRUE
J 2
(-4100 4425);
DISPLAY 0.702128 (-4100 4425);
PAINT GREEN (-4100 4425);
DISPLAY INVISIBLE (-4100 4425);
FORCEPROP 1 LAST BODY_TYPE PLUMBING
J 2
(-3775 4500);
DISPLAY 0.702128 (-3775 4500);
PAINT GREEN (-3775 4500);
DISPLAY INVISIBLE (-3775 4500);
FORCEPROP 2 LAST BOM_COST IO_SLOT
J 0
(-4275 4650);
DISPLAY 0.829787 (-4275 4650);
DISPLAY INVISIBLE (-4275 4650);
FORCEADD TAP..6
R 2
(-3775 4650);
FORCEPROP 3 LASTPIN (-3825 4650) SIG_NAME P5E_CPU0_P0_TX_C_DN<11>
J 0
(-3815 4660);
DISPLAY 0.659574 (-3815 4660);
PAINT MONO (-3815 4660);
DISPLAY INVISIBLE (-3815 4660);
FORCEPROP 1 LASTPIN (-3825 4650) BN 11
J 2
(-3773 4658);
DISPLAY 0.680851 (-3773 4658);
PAINT MONO (-3773 4658);
FORCEPROP 2 LAST CDS_LIB standard
J 0
(-3775 4650);
DISPLAY INVISIBLE (-3775 4650);
FORCEPROP 1 LAST PATH I69
J 2
(-3773 4650);
DISPLAY 0.872340 (-3773 4650);
PAINT GREEN (-3773 4650);
DISPLAY INVISIBLE (-3773 4650);
FORCEPROP 2 LAST ROOM RISER1
J 0
(-4275 4700);
DISPLAY 0.829787 (-4275 4700);
PAINT RED (-4275 4700);
DISPLAY INVISIBLE (-4275 4700);
FORCEPROP 1 LAST HDL_TAP TRUE
J 2
(-4100 4525);
DISPLAY 0.702128 (-4100 4525);
PAINT GREEN (-4100 4525);
DISPLAY INVISIBLE (-4100 4525);
FORCEPROP 1 LAST BODY_TYPE PLUMBING
J 2
(-3775 4600);
DISPLAY 0.702128 (-3775 4600);
PAINT GREEN (-3775 4600);
DISPLAY INVISIBLE (-3775 4600);
FORCEPROP 2 LAST BOM_COST IO_SLOT
J 0
(-4275 4750);
DISPLAY 0.829787 (-4275 4750);
DISPLAY INVISIBLE (-4275 4750);
FORCEADD TAP..6
(-5650 4300);
FORCEPROP 3 LASTPIN (-5600 4300) SIG_NAME P5E_CPU0_P0_TX_DP<15>
J 0
(-5590 4310);
DISPLAY 0.659574 (-5590 4310);
PAINT MONO (-5590 4310);
DISPLAY INVISIBLE (-5590 4310);
FORCEPROP 1 LASTPIN (-5600 4300) BN 15
J 0
(-5652 4308);
DISPLAY 0.680851 (-5652 4308);
PAINT MONO (-5652 4308);
FORCEPROP 2 LAST CDS_LIB standard
J 0
(-5650 4300);
DISPLAY INVISIBLE (-5650 4300);
FORCEPROP 1 LAST PATH I7
J 0
(-5652 4300);
DISPLAY 0.872340 (-5652 4300);
PAINT GREEN (-5652 4300);
DISPLAY INVISIBLE (-5652 4300);
FORCEPROP 1 LAST BODY_TYPE PLUMBING
J 0
(-5650 4250);
DISPLAY 0.574468 (-5650 4250);
PAINT GREEN (-5650 4250);
DISPLAY INVISIBLE (-5650 4250);
FORCEPROP 1 LAST HDL_TAP TRUE
J 0
(-5325 4175);
DISPLAY 0.574468 (-5325 4175);
PAINT GREEN (-5325 4175);
DISPLAY INVISIBLE (-5325 4175);
FORCEADD TAP..6
R 2
(-3775 4450);
FORCEPROP 3 LASTPIN (-3825 4450) SIG_NAME P5E_CPU0_P0_TX_C_DN<13>
J 0
(-3815 4460);
DISPLAY 0.659574 (-3815 4460);
PAINT MONO (-3815 4460);
DISPLAY INVISIBLE (-3815 4460);
FORCEPROP 1 LASTPIN (-3825 4450) BN 13
J 2
(-3773 4458);
DISPLAY 0.680851 (-3773 4458);
PAINT MONO (-3773 4458);
FORCEPROP 2 LAST CDS_LIB standard
J 0
(-3775 4450);
DISPLAY INVISIBLE (-3775 4450);
FORCEPROP 1 LAST PATH I70
J 2
(-3773 4450);
DISPLAY 0.872340 (-3773 4450);
PAINT GREEN (-3773 4450);
DISPLAY INVISIBLE (-3773 4450);
FORCEPROP 2 LAST ROOM RISER1
J 0
(-4275 4500);
DISPLAY 0.829787 (-4275 4500);
PAINT RED (-4275 4500);
DISPLAY INVISIBLE (-4275 4500);
FORCEPROP 1 LAST HDL_TAP TRUE
J 2
(-4100 4325);
DISPLAY 0.702128 (-4100 4325);
PAINT GREEN (-4100 4325);
DISPLAY INVISIBLE (-4100 4325);
FORCEPROP 1 LAST BODY_TYPE PLUMBING
J 2
(-3775 4400);
DISPLAY 0.702128 (-3775 4400);
PAINT GREEN (-3775 4400);
DISPLAY INVISIBLE (-3775 4400);
FORCEPROP 2 LAST BOM_COST IO_SLOT
J 0
(-4275 4550);
DISPLAY 0.829787 (-4275 4550);
DISPLAY INVISIBLE (-4275 4550);
FORCEADD TAP..6
R 2
(-3925 4700);
FORCEPROP 3 LASTPIN (-3975 4700) SIG_NAME P5E_CPU0_P0_TX_C_DP<11>
J 0
(-3965 4710);
DISPLAY 0.659574 (-3965 4710);
PAINT MONO (-3965 4710);
DISPLAY INVISIBLE (-3965 4710);
FORCEPROP 1 LASTPIN (-3975 4700) BN 11
J 2
(-3923 4708);
DISPLAY 0.680851 (-3923 4708);
PAINT MONO (-3923 4708);
FORCEPROP 2 LAST CDS_LIB standard
J 0
(-3925 4700);
DISPLAY INVISIBLE (-3925 4700);
FORCEPROP 1 LAST PATH I71
J 2
(-3923 4700);
DISPLAY 0.872340 (-3923 4700);
PAINT GREEN (-3923 4700);
DISPLAY INVISIBLE (-3923 4700);
FORCEPROP 2 LAST ROOM RISER1
J 0
(-4425 4750);
DISPLAY 0.829787 (-4425 4750);
PAINT RED (-4425 4750);
DISPLAY INVISIBLE (-4425 4750);
FORCEPROP 1 LAST HDL_TAP TRUE
J 2
(-4250 4575);
DISPLAY 0.702128 (-4250 4575);
PAINT GREEN (-4250 4575);
DISPLAY INVISIBLE (-4250 4575);
FORCEPROP 1 LAST BODY_TYPE PLUMBING
J 2
(-3925 4650);
DISPLAY 0.702128 (-3925 4650);
PAINT GREEN (-3925 4650);
DISPLAY INVISIBLE (-3925 4650);
FORCEPROP 2 LAST BOM_COST IO_SLOT
J 0
(-4425 4800);
DISPLAY 0.829787 (-4425 4800);
DISPLAY INVISIBLE (-4425 4800);
FORCEADD TAP..6
R 2
(-3925 4800);
FORCEPROP 3 LASTPIN (-3975 4800) SIG_NAME P5E_CPU0_P0_TX_C_DP<10>
J 0
(-3965 4810);
DISPLAY 0.659574 (-3965 4810);
PAINT MONO (-3965 4810);
DISPLAY INVISIBLE (-3965 4810);
FORCEPROP 1 LASTPIN (-3975 4800) BN 10
J 2
(-3923 4808);
DISPLAY 0.680851 (-3923 4808);
PAINT MONO (-3923 4808);
FORCEPROP 2 LAST CDS_LIB standard
J 0
(-3925 4800);
DISPLAY INVISIBLE (-3925 4800);
FORCEPROP 1 LAST PATH I72
J 2
(-3923 4800);
DISPLAY 0.872340 (-3923 4800);
PAINT GREEN (-3923 4800);
DISPLAY INVISIBLE (-3923 4800);
FORCEPROP 2 LAST ROOM RISER1
J 0
(-4425 4850);
DISPLAY 0.829787 (-4425 4850);
PAINT RED (-4425 4850);
DISPLAY INVISIBLE (-4425 4850);
FORCEPROP 1 LAST HDL_TAP TRUE
J 2
(-4250 4675);
DISPLAY 0.702128 (-4250 4675);
PAINT GREEN (-4250 4675);
DISPLAY INVISIBLE (-4250 4675);
FORCEPROP 1 LAST BODY_TYPE PLUMBING
J 2
(-3925 4750);
DISPLAY 0.702128 (-3925 4750);
PAINT GREEN (-3925 4750);
DISPLAY INVISIBLE (-3925 4750);
FORCEPROP 2 LAST BOM_COST IO_SLOT
J 0
(-4425 4900);
DISPLAY 0.829787 (-4425 4900);
DISPLAY INVISIBLE (-4425 4900);
FORCEADD TAP..6
R 2
(-3925 4900);
FORCEPROP 3 LASTPIN (-3975 4900) SIG_NAME P5E_CPU0_P0_TX_C_DP<9>
J 0
(-3965 4910);
DISPLAY 0.659574 (-3965 4910);
PAINT MONO (-3965 4910);
DISPLAY INVISIBLE (-3965 4910);
FORCEPROP 1 LASTPIN (-3975 4900) BN 9
J 2
(-3923 4908);
DISPLAY 0.680851 (-3923 4908);
PAINT MONO (-3923 4908);
FORCEPROP 2 LAST CDS_LIB standard
J 0
(-3925 4900);
DISPLAY INVISIBLE (-3925 4900);
FORCEPROP 1 LAST PATH I73
J 2
(-3923 4900);
DISPLAY 0.872340 (-3923 4900);
PAINT GREEN (-3923 4900);
DISPLAY INVISIBLE (-3923 4900);
FORCEPROP 2 LAST ROOM RISER1
J 0
(-4425 4950);
DISPLAY 0.829787 (-4425 4950);
PAINT RED (-4425 4950);
DISPLAY INVISIBLE (-4425 4950);
FORCEPROP 1 LAST HDL_TAP TRUE
J 2
(-4250 4775);
DISPLAY 0.702128 (-4250 4775);
PAINT GREEN (-4250 4775);
DISPLAY INVISIBLE (-4250 4775);
FORCEPROP 1 LAST BODY_TYPE PLUMBING
J 2
(-3925 4850);
DISPLAY 0.702128 (-3925 4850);
PAINT GREEN (-3925 4850);
DISPLAY INVISIBLE (-3925 4850);
FORCEPROP 2 LAST BOM_COST IO_SLOT
J 0
(-4425 5000);
DISPLAY 0.829787 (-4425 5000);
DISPLAY INVISIBLE (-4425 5000);
FORCEADD TAP..6
R 2
(-3775 4750);
FORCEPROP 3 LASTPIN (-3825 4750) SIG_NAME P5E_CPU0_P0_TX_C_DN<10>
J 0
(-3815 4760);
DISPLAY 0.659574 (-3815 4760);
PAINT MONO (-3815 4760);
DISPLAY INVISIBLE (-3815 4760);
FORCEPROP 1 LASTPIN (-3825 4750) BN 10
J 2
(-3773 4758);
DISPLAY 0.680851 (-3773 4758);
PAINT MONO (-3773 4758);
FORCEPROP 2 LAST CDS_LIB standard
J 0
(-3775 4750);
DISPLAY INVISIBLE (-3775 4750);
FORCEPROP 1 LAST PATH I74
J 2
(-3773 4750);
DISPLAY 0.872340 (-3773 4750);
PAINT GREEN (-3773 4750);
DISPLAY INVISIBLE (-3773 4750);
FORCEPROP 2 LAST ROOM RISER1
J 0
(-4275 4800);
DISPLAY 0.829787 (-4275 4800);
PAINT RED (-4275 4800);
DISPLAY INVISIBLE (-4275 4800);
FORCEPROP 1 LAST HDL_TAP TRUE
J 2
(-4100 4625);
DISPLAY 0.702128 (-4100 4625);
PAINT GREEN (-4100 4625);
DISPLAY INVISIBLE (-4100 4625);
FORCEPROP 1 LAST BODY_TYPE PLUMBING
J 2
(-3775 4700);
DISPLAY 0.702128 (-3775 4700);
PAINT GREEN (-3775 4700);
DISPLAY INVISIBLE (-3775 4700);
FORCEPROP 2 LAST BOM_COST IO_SLOT
J 0
(-4275 4850);
DISPLAY 0.829787 (-4275 4850);
DISPLAY INVISIBLE (-4275 4850);
FORCEADD TAP..6
R 2
(-3775 4850);
FORCEPROP 3 LASTPIN (-3825 4850) SIG_NAME P5E_CPU0_P0_TX_C_DN<9>
J 0
(-3815 4860);
DISPLAY 0.659574 (-3815 4860);
PAINT MONO (-3815 4860);
DISPLAY INVISIBLE (-3815 4860);
FORCEPROP 1 LASTPIN (-3825 4850) BN 9
J 2
(-3773 4858);
DISPLAY 0.680851 (-3773 4858);
PAINT MONO (-3773 4858);
FORCEPROP 2 LAST CDS_LIB standard
J 0
(-3775 4850);
DISPLAY INVISIBLE (-3775 4850);
FORCEPROP 1 LAST PATH I75
J 2
(-3773 4850);
DISPLAY 0.872340 (-3773 4850);
PAINT GREEN (-3773 4850);
DISPLAY INVISIBLE (-3773 4850);
FORCEPROP 2 LAST ROOM RISER1
J 0
(-4275 4900);
DISPLAY 0.829787 (-4275 4900);
PAINT RED (-4275 4900);
DISPLAY INVISIBLE (-4275 4900);
FORCEPROP 1 LAST HDL_TAP TRUE
J 2
(-4100 4725);
DISPLAY 0.702128 (-4100 4725);
PAINT GREEN (-4100 4725);
DISPLAY INVISIBLE (-4100 4725);
FORCEPROP 1 LAST BODY_TYPE PLUMBING
J 2
(-3775 4800);
DISPLAY 0.702128 (-3775 4800);
PAINT GREEN (-3775 4800);
DISPLAY INVISIBLE (-3775 4800);
FORCEPROP 2 LAST BOM_COST IO_SLOT
J 0
(-4275 4950);
DISPLAY 0.829787 (-4275 4950);
DISPLAY INVISIBLE (-4275 4950);
FORCEADD TAP..6
R 2
(-3925 5000);
FORCEPROP 3 LASTPIN (-3975 5000) SIG_NAME P5E_CPU0_P0_TX_C_DP<8>
J 0
(-3965 5010);
DISPLAY 0.659574 (-3965 5010);
PAINT MONO (-3965 5010);
DISPLAY INVISIBLE (-3965 5010);
FORCEPROP 1 LASTPIN (-3975 5000) BN 8
J 2
(-3923 5008);
DISPLAY 0.680851 (-3923 5008);
PAINT MONO (-3923 5008);
FORCEPROP 2 LAST CDS_LIB standard
J 0
(-3925 5000);
DISPLAY INVISIBLE (-3925 5000);
FORCEPROP 1 LAST PATH I76
J 2
(-3923 5000);
DISPLAY 0.872340 (-3923 5000);
PAINT GREEN (-3923 5000);
DISPLAY INVISIBLE (-3923 5000);
FORCEPROP 2 LAST ROOM RISER1
J 0
(-4425 5050);
DISPLAY 0.829787 (-4425 5050);
PAINT RED (-4425 5050);
DISPLAY INVISIBLE (-4425 5050);
FORCEPROP 1 LAST HDL_TAP TRUE
J 2
(-4250 4875);
DISPLAY 0.702128 (-4250 4875);
PAINT GREEN (-4250 4875);
DISPLAY INVISIBLE (-4250 4875);
FORCEPROP 1 LAST BODY_TYPE PLUMBING
J 2
(-3925 4950);
DISPLAY 0.702128 (-3925 4950);
PAINT GREEN (-3925 4950);
DISPLAY INVISIBLE (-3925 4950);
FORCEPROP 2 LAST BOM_COST IO_SLOT
J 0
(-4425 5100);
DISPLAY 0.829787 (-4425 5100);
DISPLAY INVISIBLE (-4425 5100);
FORCEADD TAP..6
R 2
(-3925 5100);
FORCEPROP 3 LASTPIN (-3975 5100) SIG_NAME P5E_CPU0_P0_TX_C_DP<7>
J 0
(-3965 5110);
DISPLAY 0.659574 (-3965 5110);
PAINT MONO (-3965 5110);
DISPLAY INVISIBLE (-3965 5110);
FORCEPROP 1 LASTPIN (-3975 5100) BN 7
J 2
(-3923 5108);
DISPLAY 0.680851 (-3923 5108);
PAINT MONO (-3923 5108);
FORCEPROP 2 LAST CDS_LIB standard
J 0
(-3925 5100);
DISPLAY INVISIBLE (-3925 5100);
FORCEPROP 1 LAST PATH I77
J 2
(-3923 5100);
DISPLAY 0.872340 (-3923 5100);
PAINT GREEN (-3923 5100);
DISPLAY INVISIBLE (-3923 5100);
FORCEPROP 2 LAST ROOM RISER1
J 0
(-4425 5150);
DISPLAY 0.829787 (-4425 5150);
PAINT RED (-4425 5150);
DISPLAY INVISIBLE (-4425 5150);
FORCEPROP 1 LAST HDL_TAP TRUE
J 2
(-4250 4975);
DISPLAY 0.702128 (-4250 4975);
PAINT GREEN (-4250 4975);
DISPLAY INVISIBLE (-4250 4975);
FORCEPROP 1 LAST BODY_TYPE PLUMBING
J 2
(-3925 5050);
DISPLAY 0.702128 (-3925 5050);
PAINT GREEN (-3925 5050);
DISPLAY INVISIBLE (-3925 5050);
FORCEPROP 2 LAST BOM_COST IO_SLOT
J 0
(-4425 5200);
DISPLAY 0.829787 (-4425 5200);
DISPLAY INVISIBLE (-4425 5200);
FORCEADD TAP..6
R 2
(-3775 5150);
FORCEPROP 3 LASTPIN (-3825 5150) SIG_NAME P5E_CPU0_P0_TX_C_DN<6>
J 0
(-3815 5160);
DISPLAY 0.659574 (-3815 5160);
PAINT MONO (-3815 5160);
DISPLAY INVISIBLE (-3815 5160);
FORCEPROP 1 LASTPIN (-3825 5150) BN 6
J 2
(-3773 5158);
DISPLAY 0.680851 (-3773 5158);
PAINT MONO (-3773 5158);
FORCEPROP 2 LAST CDS_LIB standard
J 0
(-3775 5150);
DISPLAY INVISIBLE (-3775 5150);
FORCEPROP 1 LAST PATH I78
J 2
(-3773 5150);
DISPLAY 0.872340 (-3773 5150);
PAINT GREEN (-3773 5150);
DISPLAY INVISIBLE (-3773 5150);
FORCEPROP 2 LAST ROOM RISER1
J 0
(-4275 5200);
DISPLAY 0.829787 (-4275 5200);
PAINT RED (-4275 5200);
DISPLAY INVISIBLE (-4275 5200);
FORCEPROP 1 LAST HDL_TAP TRUE
J 2
(-4100 5025);
DISPLAY 0.702128 (-4100 5025);
PAINT GREEN (-4100 5025);
DISPLAY INVISIBLE (-4100 5025);
FORCEPROP 1 LAST BODY_TYPE PLUMBING
J 2
(-3775 5100);
DISPLAY 0.702128 (-3775 5100);
PAINT GREEN (-3775 5100);
DISPLAY INVISIBLE (-3775 5100);
FORCEPROP 2 LAST BOM_COST IO_SLOT
J 0
(-4275 5250);
DISPLAY 0.829787 (-4275 5250);
DISPLAY INVISIBLE (-4275 5250);
FORCEADD TAP..6
R 2
(-3775 5050);
FORCEPROP 3 LASTPIN (-3825 5050) SIG_NAME P5E_CPU0_P0_TX_C_DN<7>
J 0
(-3815 5060);
DISPLAY 0.659574 (-3815 5060);
PAINT MONO (-3815 5060);
DISPLAY INVISIBLE (-3815 5060);
FORCEPROP 1 LASTPIN (-3825 5050) BN 7
J 2
(-3773 5058);
DISPLAY 0.680851 (-3773 5058);
PAINT MONO (-3773 5058);
FORCEPROP 2 LAST CDS_LIB standard
J 0
(-3775 5050);
DISPLAY INVISIBLE (-3775 5050);
FORCEPROP 1 LAST PATH I79
J 2
(-3773 5050);
DISPLAY 0.872340 (-3773 5050);
PAINT GREEN (-3773 5050);
DISPLAY INVISIBLE (-3773 5050);
FORCEPROP 2 LAST ROOM RISER1
J 0
(-4275 5100);
DISPLAY 0.829787 (-4275 5100);
PAINT RED (-4275 5100);
DISPLAY INVISIBLE (-4275 5100);
FORCEPROP 1 LAST HDL_TAP TRUE
J 2
(-4100 4925);
DISPLAY 0.702128 (-4100 4925);
PAINT GREEN (-4100 4925);
DISPLAY INVISIBLE (-4100 4925);
FORCEPROP 1 LAST BODY_TYPE PLUMBING
J 2
(-3775 5000);
DISPLAY 0.702128 (-3775 5000);
PAINT GREEN (-3775 5000);
DISPLAY INVISIBLE (-3775 5000);
FORCEPROP 2 LAST BOM_COST IO_SLOT
J 0
(-4275 5150);
DISPLAY 0.829787 (-4275 5150);
DISPLAY INVISIBLE (-4275 5150);
FORCEADD TAP..6
(-5650 4400);
FORCEPROP 3 LASTPIN (-5600 4400) SIG_NAME P5E_CPU0_P0_TX_DP<14>
J 0
(-5590 4410);
DISPLAY 0.659574 (-5590 4410);
PAINT MONO (-5590 4410);
DISPLAY INVISIBLE (-5590 4410);
FORCEPROP 1 LASTPIN (-5600 4400) BN 14
J 0
(-5652 4408);
DISPLAY 0.680851 (-5652 4408);
PAINT MONO (-5652 4408);
FORCEPROP 2 LAST CDS_LIB standard
J 0
(-5650 4400);
DISPLAY INVISIBLE (-5650 4400);
FORCEPROP 1 LAST PATH I8
J 0
(-5652 4400);
DISPLAY 0.872340 (-5652 4400);
PAINT GREEN (-5652 4400);
DISPLAY INVISIBLE (-5652 4400);
FORCEPROP 1 LAST BODY_TYPE PLUMBING
J 0
(-5650 4350);
DISPLAY 0.574468 (-5650 4350);
PAINT GREEN (-5650 4350);
DISPLAY INVISIBLE (-5650 4350);
FORCEPROP 1 LAST HDL_TAP TRUE
J 0
(-5325 4275);
DISPLAY 0.574468 (-5325 4275);
PAINT GREEN (-5325 4275);
DISPLAY INVISIBLE (-5325 4275);
FORCEADD TAP..6
R 2
(-3775 4950);
FORCEPROP 3 LASTPIN (-3825 4950) SIG_NAME P5E_CPU0_P0_TX_C_DN<8>
J 0
(-3815 4960);
DISPLAY 0.659574 (-3815 4960);
PAINT MONO (-3815 4960);
DISPLAY INVISIBLE (-3815 4960);
FORCEPROP 1 LASTPIN (-3825 4950) BN 8
J 2
(-3773 4958);
DISPLAY 0.680851 (-3773 4958);
PAINT MONO (-3773 4958);
FORCEPROP 2 LAST CDS_LIB standard
J 0
(-3775 4950);
DISPLAY INVISIBLE (-3775 4950);
FORCEPROP 1 LAST PATH I80
J 2
(-3773 4950);
DISPLAY 0.872340 (-3773 4950);
PAINT GREEN (-3773 4950);
DISPLAY INVISIBLE (-3773 4950);
FORCEPROP 2 LAST ROOM RISER1
J 0
(-4275 5000);
DISPLAY 0.829787 (-4275 5000);
PAINT RED (-4275 5000);
DISPLAY INVISIBLE (-4275 5000);
FORCEPROP 1 LAST HDL_TAP TRUE
J 2
(-4100 4825);
DISPLAY 0.702128 (-4100 4825);
PAINT GREEN (-4100 4825);
DISPLAY INVISIBLE (-4100 4825);
FORCEPROP 1 LAST BODY_TYPE PLUMBING
J 2
(-3775 4900);
DISPLAY 0.702128 (-3775 4900);
PAINT GREEN (-3775 4900);
DISPLAY INVISIBLE (-3775 4900);
FORCEPROP 2 LAST BOM_COST IO_SLOT
J 0
(-4275 5050);
DISPLAY 0.829787 (-4275 5050);
DISPLAY INVISIBLE (-4275 5050);
FORCEADD TAP..6
R 2
(-3925 5200);
FORCEPROP 3 LASTPIN (-3975 5200) SIG_NAME P5E_CPU0_P0_TX_C_DP<6>
J 0
(-3965 5210);
DISPLAY 0.659574 (-3965 5210);
PAINT MONO (-3965 5210);
DISPLAY INVISIBLE (-3965 5210);
FORCEPROP 1 LASTPIN (-3975 5200) BN 6
J 2
(-3923 5208);
DISPLAY 0.680851 (-3923 5208);
PAINT MONO (-3923 5208);
FORCEPROP 2 LAST CDS_LIB standard
J 0
(-3925 5200);
DISPLAY INVISIBLE (-3925 5200);
FORCEPROP 1 LAST PATH I81
J 2
(-3923 5200);
DISPLAY 0.872340 (-3923 5200);
PAINT GREEN (-3923 5200);
DISPLAY INVISIBLE (-3923 5200);
FORCEPROP 2 LAST ROOM RISER1
J 0
(-4425 5250);
DISPLAY 0.829787 (-4425 5250);
PAINT RED (-4425 5250);
DISPLAY INVISIBLE (-4425 5250);
FORCEPROP 1 LAST HDL_TAP TRUE
J 2
(-4250 5075);
DISPLAY 0.702128 (-4250 5075);
PAINT GREEN (-4250 5075);
DISPLAY INVISIBLE (-4250 5075);
FORCEPROP 1 LAST BODY_TYPE PLUMBING
J 2
(-3925 5150);
DISPLAY 0.702128 (-3925 5150);
PAINT GREEN (-3925 5150);
DISPLAY INVISIBLE (-3925 5150);
FORCEPROP 2 LAST BOM_COST IO_SLOT
J 0
(-4425 5300);
DISPLAY 0.829787 (-4425 5300);
DISPLAY INVISIBLE (-4425 5300);
FORCEADD TAP..6
R 2
(-3925 5300);
FORCEPROP 3 LASTPIN (-3975 5300) SIG_NAME P5E_CPU0_P0_TX_C_DP<5>
J 0
(-3965 5310);
DISPLAY 0.659574 (-3965 5310);
PAINT MONO (-3965 5310);
DISPLAY INVISIBLE (-3965 5310);
FORCEPROP 1 LASTPIN (-3975 5300) BN 5
J 2
(-3923 5308);
DISPLAY 0.680851 (-3923 5308);
PAINT MONO (-3923 5308);
FORCEPROP 2 LAST CDS_LIB standard
J 0
(-3925 5300);
DISPLAY INVISIBLE (-3925 5300);
FORCEPROP 1 LAST PATH I82
J 2
(-3923 5300);
DISPLAY 0.872340 (-3923 5300);
PAINT GREEN (-3923 5300);
DISPLAY INVISIBLE (-3923 5300);
FORCEPROP 2 LAST ROOM RISER1
J 0
(-4425 5350);
DISPLAY 0.829787 (-4425 5350);
PAINT RED (-4425 5350);
DISPLAY INVISIBLE (-4425 5350);
FORCEPROP 1 LAST HDL_TAP TRUE
J 2
(-4250 5175);
DISPLAY 0.702128 (-4250 5175);
PAINT GREEN (-4250 5175);
DISPLAY INVISIBLE (-4250 5175);
FORCEPROP 1 LAST BODY_TYPE PLUMBING
J 2
(-3925 5250);
DISPLAY 0.702128 (-3925 5250);
PAINT GREEN (-3925 5250);
DISPLAY INVISIBLE (-3925 5250);
FORCEPROP 2 LAST BOM_COST IO_SLOT
J 0
(-4425 5400);
DISPLAY 0.829787 (-4425 5400);
DISPLAY INVISIBLE (-4425 5400);
FORCEADD TAP..6
R 2
(-3925 5400);
FORCEPROP 3 LASTPIN (-3975 5400) SIG_NAME P5E_CPU0_P0_TX_C_DP<4>
J 0
(-3965 5410);
DISPLAY 0.659574 (-3965 5410);
PAINT MONO (-3965 5410);
DISPLAY INVISIBLE (-3965 5410);
FORCEPROP 1 LASTPIN (-3975 5400) BN 4
J 2
(-3923 5408);
DISPLAY 0.680851 (-3923 5408);
PAINT MONO (-3923 5408);
FORCEPROP 2 LAST CDS_LIB standard
J 0
(-3925 5400);
DISPLAY INVISIBLE (-3925 5400);
FORCEPROP 1 LAST PATH I83
J 2
(-3923 5400);
DISPLAY 0.872340 (-3923 5400);
PAINT GREEN (-3923 5400);
DISPLAY INVISIBLE (-3923 5400);
FORCEPROP 2 LAST ROOM RISER1
J 0
(-4425 5450);
DISPLAY 0.829787 (-4425 5450);
PAINT RED (-4425 5450);
DISPLAY INVISIBLE (-4425 5450);
FORCEPROP 1 LAST HDL_TAP TRUE
J 2
(-4250 5275);
DISPLAY 0.702128 (-4250 5275);
PAINT GREEN (-4250 5275);
DISPLAY INVISIBLE (-4250 5275);
FORCEPROP 1 LAST BODY_TYPE PLUMBING
J 2
(-3925 5350);
DISPLAY 0.702128 (-3925 5350);
PAINT GREEN (-3925 5350);
DISPLAY INVISIBLE (-3925 5350);
FORCEPROP 2 LAST BOM_COST IO_SLOT
J 0
(-4425 5500);
DISPLAY 0.829787 (-4425 5500);
DISPLAY INVISIBLE (-4425 5500);
FORCEADD TAP..6
R 2
(-3775 5250);
FORCEPROP 3 LASTPIN (-3825 5250) SIG_NAME P5E_CPU0_P0_TX_C_DN<5>
J 0
(-3815 5260);
DISPLAY 0.659574 (-3815 5260);
PAINT MONO (-3815 5260);
DISPLAY INVISIBLE (-3815 5260);
FORCEPROP 1 LASTPIN (-3825 5250) BN 5
J 2
(-3773 5258);
DISPLAY 0.680851 (-3773 5258);
PAINT MONO (-3773 5258);
FORCEPROP 2 LAST CDS_LIB standard
J 0
(-3775 5250);
DISPLAY INVISIBLE (-3775 5250);
FORCEPROP 1 LAST PATH I84
J 2
(-3773 5250);
DISPLAY 0.872340 (-3773 5250);
PAINT GREEN (-3773 5250);
DISPLAY INVISIBLE (-3773 5250);
FORCEPROP 2 LAST ROOM RISER1
J 0
(-4275 5300);
DISPLAY 0.829787 (-4275 5300);
PAINT RED (-4275 5300);
DISPLAY INVISIBLE (-4275 5300);
FORCEPROP 1 LAST HDL_TAP TRUE
J 2
(-4100 5125);
DISPLAY 0.702128 (-4100 5125);
PAINT GREEN (-4100 5125);
DISPLAY INVISIBLE (-4100 5125);
FORCEPROP 1 LAST BODY_TYPE PLUMBING
J 2
(-3775 5200);
DISPLAY 0.702128 (-3775 5200);
PAINT GREEN (-3775 5200);
DISPLAY INVISIBLE (-3775 5200);
FORCEPROP 2 LAST BOM_COST IO_SLOT
J 0
(-4275 5350);
DISPLAY 0.829787 (-4275 5350);
DISPLAY INVISIBLE (-4275 5350);
FORCEADD TAP..6
R 2
(-3775 5350);
FORCEPROP 3 LASTPIN (-3825 5350) SIG_NAME P5E_CPU0_P0_TX_C_DN<4>
J 0
(-3815 5360);
DISPLAY 0.659574 (-3815 5360);
PAINT MONO (-3815 5360);
DISPLAY INVISIBLE (-3815 5360);
FORCEPROP 1 LASTPIN (-3825 5350) BN 4
J 2
(-3773 5358);
DISPLAY 0.680851 (-3773 5358);
PAINT MONO (-3773 5358);
FORCEPROP 2 LAST CDS_LIB standard
J 0
(-3775 5350);
DISPLAY INVISIBLE (-3775 5350);
FORCEPROP 1 LAST PATH I85
J 2
(-3773 5350);
DISPLAY 0.872340 (-3773 5350);
PAINT GREEN (-3773 5350);
DISPLAY INVISIBLE (-3773 5350);
FORCEPROP 2 LAST ROOM RISER1
J 0
(-4275 5400);
DISPLAY 0.829787 (-4275 5400);
PAINT RED (-4275 5400);
DISPLAY INVISIBLE (-4275 5400);
FORCEPROP 1 LAST HDL_TAP TRUE
J 2
(-4100 5225);
DISPLAY 0.702128 (-4100 5225);
PAINT GREEN (-4100 5225);
DISPLAY INVISIBLE (-4100 5225);
FORCEPROP 1 LAST BODY_TYPE PLUMBING
J 2
(-3775 5300);
DISPLAY 0.702128 (-3775 5300);
PAINT GREEN (-3775 5300);
DISPLAY INVISIBLE (-3775 5300);
FORCEPROP 2 LAST BOM_COST IO_SLOT
J 0
(-4275 5450);
DISPLAY 0.829787 (-4275 5450);
DISPLAY INVISIBLE (-4275 5450);
FORCEADD TAP..6
R 2
(-3775 5450);
FORCEPROP 3 LASTPIN (-3825 5450) SIG_NAME P5E_CPU0_P0_TX_C_DN<3>
J 0
(-3815 5460);
DISPLAY 0.659574 (-3815 5460);
PAINT MONO (-3815 5460);
DISPLAY INVISIBLE (-3815 5460);
FORCEPROP 1 LASTPIN (-3825 5450) BN 3
J 2
(-3773 5458);
DISPLAY 0.680851 (-3773 5458);
PAINT MONO (-3773 5458);
FORCEPROP 2 LAST CDS_LIB standard
J 0
(-3775 5450);
DISPLAY INVISIBLE (-3775 5450);
FORCEPROP 1 LAST PATH I86
J 2
(-3773 5450);
DISPLAY 0.872340 (-3773 5450);
PAINT GREEN (-3773 5450);
DISPLAY INVISIBLE (-3773 5450);
FORCEPROP 2 LAST ROOM RISER1
J 0
(-4275 5500);
DISPLAY 0.829787 (-4275 5500);
PAINT RED (-4275 5500);
DISPLAY INVISIBLE (-4275 5500);
FORCEPROP 1 LAST HDL_TAP TRUE
J 2
(-4100 5325);
DISPLAY 0.702128 (-4100 5325);
PAINT GREEN (-4100 5325);
DISPLAY INVISIBLE (-4100 5325);
FORCEPROP 1 LAST BODY_TYPE PLUMBING
J 2
(-3775 5400);
DISPLAY 0.702128 (-3775 5400);
PAINT GREEN (-3775 5400);
DISPLAY INVISIBLE (-3775 5400);
FORCEPROP 2 LAST BOM_COST IO_SLOT
J 0
(-4275 5550);
DISPLAY 0.829787 (-4275 5550);
DISPLAY INVISIBLE (-4275 5550);
FORCEADD TAP..6
R 2
(-3925 5500);
FORCEPROP 3 LASTPIN (-3975 5500) SIG_NAME P5E_CPU0_P0_TX_C_DP<3>
J 0
(-3965 5510);
DISPLAY 0.659574 (-3965 5510);
PAINT MONO (-3965 5510);
DISPLAY INVISIBLE (-3965 5510);
FORCEPROP 1 LASTPIN (-3975 5500) BN 3
J 2
(-3923 5508);
DISPLAY 0.680851 (-3923 5508);
PAINT MONO (-3923 5508);
FORCEPROP 2 LAST CDS_LIB standard
J 0
(-3925 5500);
DISPLAY INVISIBLE (-3925 5500);
FORCEPROP 1 LAST PATH I87
J 2
(-3923 5500);
DISPLAY 0.872340 (-3923 5500);
PAINT GREEN (-3923 5500);
DISPLAY INVISIBLE (-3923 5500);
FORCEPROP 2 LAST ROOM RISER1
J 0
(-4425 5550);
DISPLAY 0.829787 (-4425 5550);
PAINT RED (-4425 5550);
DISPLAY INVISIBLE (-4425 5550);
FORCEPROP 1 LAST HDL_TAP TRUE
J 2
(-4250 5375);
DISPLAY 0.702128 (-4250 5375);
PAINT GREEN (-4250 5375);
DISPLAY INVISIBLE (-4250 5375);
FORCEPROP 1 LAST BODY_TYPE PLUMBING
J 2
(-3925 5450);
DISPLAY 0.702128 (-3925 5450);
PAINT GREEN (-3925 5450);
DISPLAY INVISIBLE (-3925 5450);
FORCEPROP 2 LAST BOM_COST IO_SLOT
J 0
(-4425 5600);
DISPLAY 0.829787 (-4425 5600);
DISPLAY INVISIBLE (-4425 5600);
FORCEADD TAP..6
R 2
(-3925 5700);
FORCEPROP 3 LASTPIN (-3975 5700) SIG_NAME P5E_CPU0_P0_TX_C_DP<1>
J 0
(-3965 5710);
DISPLAY 0.659574 (-3965 5710);
PAINT MONO (-3965 5710);
DISPLAY INVISIBLE (-3965 5710);
FORCEPROP 1 LASTPIN (-3975 5700) BN 1
J 2
(-3923 5708);
DISPLAY 0.680851 (-3923 5708);
PAINT MONO (-3923 5708);
FORCEPROP 2 LAST CDS_LIB standard
J 0
(-3925 5700);
DISPLAY INVISIBLE (-3925 5700);
FORCEPROP 1 LAST PATH I88
J 2
(-3923 5700);
DISPLAY 0.872340 (-3923 5700);
PAINT GREEN (-3923 5700);
DISPLAY INVISIBLE (-3923 5700);
FORCEPROP 2 LAST ROOM RISER1
J 0
(-4425 5750);
DISPLAY 0.829787 (-4425 5750);
PAINT RED (-4425 5750);
DISPLAY INVISIBLE (-4425 5750);
FORCEPROP 1 LAST HDL_TAP TRUE
J 2
(-4250 5575);
DISPLAY 0.702128 (-4250 5575);
PAINT GREEN (-4250 5575);
DISPLAY INVISIBLE (-4250 5575);
FORCEPROP 1 LAST BODY_TYPE PLUMBING
J 2
(-3925 5650);
DISPLAY 0.702128 (-3925 5650);
PAINT GREEN (-3925 5650);
DISPLAY INVISIBLE (-3925 5650);
FORCEPROP 2 LAST BOM_COST IO_SLOT
J 0
(-4425 5800);
DISPLAY 0.829787 (-4425 5800);
DISPLAY INVISIBLE (-4425 5800);
FORCEADD TAP..6
R 2
(-3925 5600);
FORCEPROP 3 LASTPIN (-3975 5600) SIG_NAME P5E_CPU0_P0_TX_C_DP<2>
J 0
(-3965 5610);
DISPLAY 0.659574 (-3965 5610);
PAINT MONO (-3965 5610);
DISPLAY INVISIBLE (-3965 5610);
FORCEPROP 1 LASTPIN (-3975 5600) BN 2
J 2
(-3923 5608);
DISPLAY 0.680851 (-3923 5608);
PAINT MONO (-3923 5608);
FORCEPROP 2 LAST CDS_LIB standard
J 0
(-3925 5600);
DISPLAY INVISIBLE (-3925 5600);
FORCEPROP 1 LAST PATH I89
J 2
(-3923 5600);
DISPLAY 0.872340 (-3923 5600);
PAINT GREEN (-3923 5600);
DISPLAY INVISIBLE (-3923 5600);
FORCEPROP 2 LAST ROOM RISER1
J 0
(-4425 5650);
DISPLAY 0.829787 (-4425 5650);
PAINT RED (-4425 5650);
DISPLAY INVISIBLE (-4425 5650);
FORCEPROP 1 LAST HDL_TAP TRUE
J 2
(-4250 5475);
DISPLAY 0.702128 (-4250 5475);
PAINT GREEN (-4250 5475);
DISPLAY INVISIBLE (-4250 5475);
FORCEPROP 1 LAST BODY_TYPE PLUMBING
J 2
(-3925 5550);
DISPLAY 0.702128 (-3925 5550);
PAINT GREEN (-3925 5550);
DISPLAY INVISIBLE (-3925 5550);
FORCEPROP 2 LAST BOM_COST IO_SLOT
J 0
(-4425 5700);
DISPLAY 0.829787 (-4425 5700);
DISPLAY INVISIBLE (-4425 5700);
FORCEADD TAP..6
(-5650 4500);
FORCEPROP 3 LASTPIN (-5600 4500) SIG_NAME P5E_CPU0_P0_TX_DP<13>
J 0
(-5590 4510);
DISPLAY 0.659574 (-5590 4510);
PAINT MONO (-5590 4510);
DISPLAY INVISIBLE (-5590 4510);
FORCEPROP 1 LASTPIN (-5600 4500) BN 13
J 0
(-5652 4508);
DISPLAY 0.680851 (-5652 4508);
PAINT MONO (-5652 4508);
FORCEPROP 2 LAST CDS_LIB standard
J 0
(-5650 4500);
DISPLAY INVISIBLE (-5650 4500);
FORCEPROP 1 LAST PATH I9
J 0
(-5652 4500);
DISPLAY 0.872340 (-5652 4500);
PAINT GREEN (-5652 4500);
DISPLAY INVISIBLE (-5652 4500);
FORCEPROP 1 LAST BODY_TYPE PLUMBING
J 0
(-5650 4450);
DISPLAY 0.574468 (-5650 4450);
PAINT GREEN (-5650 4450);
DISPLAY INVISIBLE (-5650 4450);
FORCEPROP 1 LAST HDL_TAP TRUE
J 0
(-5325 4375);
DISPLAY 0.574468 (-5325 4375);
PAINT GREEN (-5325 4375);
DISPLAY INVISIBLE (-5325 4375);
FORCEADD TAP..6
R 2
(-3775 5650);
FORCEPROP 3 LASTPIN (-3825 5650) SIG_NAME P5E_CPU0_P0_TX_C_DN<1>
J 0
(-3815 5660);
DISPLAY 0.659574 (-3815 5660);
PAINT MONO (-3815 5660);
DISPLAY INVISIBLE (-3815 5660);
FORCEPROP 1 LASTPIN (-3825 5650) BN 1
J 2
(-3773 5658);
DISPLAY 0.680851 (-3773 5658);
PAINT MONO (-3773 5658);
FORCEPROP 2 LAST CDS_LIB standard
J 0
(-3775 5650);
DISPLAY INVISIBLE (-3775 5650);
FORCEPROP 1 LAST PATH I90
J 2
(-3773 5650);
DISPLAY 0.872340 (-3773 5650);
PAINT GREEN (-3773 5650);
DISPLAY INVISIBLE (-3773 5650);
FORCEPROP 2 LAST ROOM RISER1
J 0
(-4275 5700);
DISPLAY 0.829787 (-4275 5700);
PAINT RED (-4275 5700);
DISPLAY INVISIBLE (-4275 5700);
FORCEPROP 1 LAST HDL_TAP TRUE
J 2
(-4100 5525);
DISPLAY 0.702128 (-4100 5525);
PAINT GREEN (-4100 5525);
DISPLAY INVISIBLE (-4100 5525);
FORCEPROP 1 LAST BODY_TYPE PLUMBING
J 2
(-3775 5600);
DISPLAY 0.702128 (-3775 5600);
PAINT GREEN (-3775 5600);
DISPLAY INVISIBLE (-3775 5600);
FORCEPROP 2 LAST BOM_COST IO_SLOT
J 0
(-4275 5750);
DISPLAY 0.829787 (-4275 5750);
DISPLAY INVISIBLE (-4275 5750);
FORCEADD TAP..6
R 2
(-3775 5550);
FORCEPROP 3 LASTPIN (-3825 5550) SIG_NAME P5E_CPU0_P0_TX_C_DN<2>
J 0
(-3815 5560);
DISPLAY 0.659574 (-3815 5560);
PAINT MONO (-3815 5560);
DISPLAY INVISIBLE (-3815 5560);
FORCEPROP 1 LASTPIN (-3825 5550) BN 2
J 2
(-3773 5558);
DISPLAY 0.680851 (-3773 5558);
PAINT MONO (-3773 5558);
FORCEPROP 2 LAST CDS_LIB standard
J 0
(-3775 5550);
DISPLAY INVISIBLE (-3775 5550);
FORCEPROP 1 LAST PATH I91
J 2
(-3773 5550);
DISPLAY 0.872340 (-3773 5550);
PAINT GREEN (-3773 5550);
DISPLAY INVISIBLE (-3773 5550);
FORCEPROP 2 LAST ROOM RISER1
J 0
(-4275 5600);
DISPLAY 0.829787 (-4275 5600);
PAINT RED (-4275 5600);
DISPLAY INVISIBLE (-4275 5600);
FORCEPROP 1 LAST HDL_TAP TRUE
J 2
(-4100 5425);
DISPLAY 0.702128 (-4100 5425);
PAINT GREEN (-4100 5425);
DISPLAY INVISIBLE (-4100 5425);
FORCEPROP 1 LAST BODY_TYPE PLUMBING
J 2
(-3775 5500);
DISPLAY 0.702128 (-3775 5500);
PAINT GREEN (-3775 5500);
DISPLAY INVISIBLE (-3775 5500);
FORCEPROP 2 LAST BOM_COST IO_SLOT
J 0
(-4275 5650);
DISPLAY 0.829787 (-4275 5650);
DISPLAY INVISIBLE (-4275 5650);
FORCEADD TAP..6
R 2
(-3925 5800);
FORCEPROP 3 LASTPIN (-3975 5800) SIG_NAME P5E_CPU0_P0_TX_C_DP<0>
J 0
(-3965 5810);
DISPLAY 0.659574 (-3965 5810);
PAINT MONO (-3965 5810);
DISPLAY INVISIBLE (-3965 5810);
FORCEPROP 1 LASTPIN (-3975 5800) BN 0
J 2
(-3923 5808);
DISPLAY 0.680851 (-3923 5808);
PAINT MONO (-3923 5808);
FORCEPROP 2 LAST CDS_LIB standard
J 0
(-3925 5800);
DISPLAY INVISIBLE (-3925 5800);
FORCEPROP 1 LAST PATH I92
J 2
(-3923 5800);
DISPLAY 0.872340 (-3923 5800);
PAINT GREEN (-3923 5800);
DISPLAY INVISIBLE (-3923 5800);
FORCEPROP 2 LAST ROOM RISER1
J 0
(-4425 5850);
DISPLAY 0.829787 (-4425 5850);
PAINT RED (-4425 5850);
DISPLAY INVISIBLE (-4425 5850);
FORCEPROP 1 LAST HDL_TAP TRUE
J 2
(-4250 5675);
DISPLAY 0.702128 (-4250 5675);
PAINT GREEN (-4250 5675);
DISPLAY INVISIBLE (-4250 5675);
FORCEPROP 1 LAST BODY_TYPE PLUMBING
J 2
(-3925 5750);
DISPLAY 0.702128 (-3925 5750);
PAINT GREEN (-3925 5750);
DISPLAY INVISIBLE (-3925 5750);
FORCEPROP 2 LAST BOM_COST IO_SLOT
J 0
(-4425 5900);
DISPLAY 0.829787 (-4425 5900);
DISPLAY INVISIBLE (-4425 5900);
FORCEADD TAP..6
R 2
(-3775 5750);
FORCEPROP 3 LASTPIN (-3825 5750) SIG_NAME P5E_CPU0_P0_TX_C_DN<0>
J 0
(-3815 5760);
DISPLAY 0.659574 (-3815 5760);
PAINT MONO (-3815 5760);
DISPLAY INVISIBLE (-3815 5760);
FORCEPROP 1 LASTPIN (-3825 5750) BN 0
J 2
(-3773 5758);
DISPLAY 0.680851 (-3773 5758);
PAINT MONO (-3773 5758);
FORCEPROP 2 LAST CDS_LIB standard
J 0
(-3775 5750);
DISPLAY INVISIBLE (-3775 5750);
FORCEPROP 1 LAST PATH I93
J 2
(-3773 5750);
DISPLAY 0.872340 (-3773 5750);
PAINT GREEN (-3773 5750);
DISPLAY INVISIBLE (-3773 5750);
FORCEPROP 2 LAST ROOM RISER1
J 0
(-4275 5800);
DISPLAY 0.829787 (-4275 5800);
PAINT RED (-4275 5800);
DISPLAY INVISIBLE (-4275 5800);
FORCEPROP 1 LAST HDL_TAP TRUE
J 2
(-4100 5625);
DISPLAY 0.702128 (-4100 5625);
PAINT GREEN (-4100 5625);
DISPLAY INVISIBLE (-4100 5625);
FORCEPROP 1 LAST BODY_TYPE PLUMBING
J 2
(-3775 5700);
DISPLAY 0.702128 (-3775 5700);
PAINT GREEN (-3775 5700);
DISPLAY INVISIBLE (-3775 5700);
FORCEPROP 2 LAST BOM_COST IO_SLOT
J 0
(-4275 5850);
DISPLAY 0.829787 (-4275 5850);
DISPLAY INVISIBLE (-4275 5850);
FORCEADD OFFPAGE..2
(-2800 5975);
FORCEPROP 2 LAST CDS_LIB standard
J 0
(-2800 5975);
DISPLAY INVISIBLE (-2800 5975);
FORCEPROP 2 LAST PATH I94
J 0
(-2625 6050);
DISPLAY 0.680851 (-2625 6050);
DISPLAY INVISIBLE (-2625 6050);
FORCEPROP 1 LAST OFFPAGE TRUE
J 0
(-2475 5850);
DISPLAY 0.872340 (-2475 5850);
PAINT GREEN (-2475 5850);
DISPLAY INVISIBLE (-2475 5850);
FORCEPROP 1 LAST COMMENT_BODY TRUE
J 0
(-2845 5880);
DISPLAY 0.872340 (-2845 5880);
PAINT GREEN (-2845 5880);
DISPLAY INVISIBLE (-2845 5880);
FORCEADD OFFPAGE..2
(-2800 6025);
FORCEPROP 2 LAST CDS_LIB standard
J 0
(-2800 6025);
DISPLAY INVISIBLE (-2800 6025);
FORCEPROP 2 LAST PATH I95
J 0
(-2625 6100);
DISPLAY 0.680851 (-2625 6100);
DISPLAY INVISIBLE (-2625 6100);
FORCEPROP 1 LAST OFFPAGE TRUE
J 0
(-2475 5900);
DISPLAY 0.872340 (-2475 5900);
PAINT GREEN (-2475 5900);
DISPLAY INVISIBLE (-2475 5900);
FORCEPROP 1 LAST COMMENT_BODY TRUE
J 0
(-2845 5930);
DISPLAY 0.872340 (-2845 5930);
PAINT GREEN (-2845 5930);
DISPLAY INVISIBLE (-2845 5930);
FORCEADD Q_CAP_DIFFBUS..2
R 2
(-4925 4850);
FORCEPROP 1 LAST LOCATION C520
J 2
(-4725 4850);
DISPLAY 0.723404 (-4725 4850);
PAINT GREEN (-4725 4850);
FORCEPROP 0 LAST $SEC 1
J 0
(-4725 4900);
DISPLAY 0.680851 (-4725 4900);
PAINT MONO (-4725 4900);
DISPLAY INVISIBLE (-4725 4900);
FORCEPROP 0 LAST CDS_SEC 1
J 0
(-4725 4900);
DISPLAY 0.680851 (-4725 4900);
DISPLAY INVISIBLE (-4725 4900);
FORCEPROP 0 LASTPIN (-4850 4850) $PN 1
J 0
(-4840 4860);
DISPLAY 0.680851 (-4840 4860);
PAINT MONO (-4840 4860);
FORCEPROP 0 LASTPIN (-5000 4850) $PN 2
J 2
(-5010 4860);
DISPLAY 0.680851 (-5010 4860);
PAINT MONO (-5010 4860);
FORCEPROP 2 LAST VALUE DIFF BUS_0.22UF
J 2
(-5050 4850);
DISPLAY 0.553191 (-5050 4850);
FORCEPROP 1 LAST CDS_LMAN_SYM_OUTLINE -25,50,25,-50
J 2
(-4925 4850);
DISPLAY 0.468085 (-4925 4850);
PAINT GREEN (-4925 4850);
DISPLAY INVISIBLE (-4925 4850);
FORCEPROP 2 LAST CDS_LIB pure_quanta
J 0
(-4925 4850);
DISPLAY INVISIBLE (-4925 4850);
FORCEPROP 1 LAST PATH I96
J 2
(-4925 4850);
DISPLAY 0.723404 (-4925 4850);
DISPLAY INVISIBLE (-4925 4850);
FORCEPROP 0 LAST VOLTAGE 6.3V
J 2
(-5000 5025);
DISPLAY 0.680851 (-5000 5025);
DISPLAY INVISIBLE (-5000 5025);
FORCEPROP 0 LAST TOLERANCE 20%
J 2
(-5000 4975);
DISPLAY 0.680851 (-5000 4975);
DISPLAY INVISIBLE (-5000 4975);
FORCEPROP 1 LAST PART_NUMBER SP_CH4221MEE01
J 2
(-4900 4925);
DISPLAY 0.723404 (-4900 4925);
PAINT GREEN (-4900 4925);
DISPLAY INVISIBLE (-4900 4925);
FORCEPROP 1 LAST MATERIAL X6S
J 2
(-4775 4900);
DISPLAY 0.723404 (-4775 4900);
PAINT GREEN (-4775 4900);
DISPLAY INVISIBLE (-4775 4900);
FORCEPROP 1 LAST PIN_NAMES_ROTATE True
J 2
(-4925 4850);
DISPLAY 0.489362 (-4925 4850);
PAINT GREEN (-4925 4850);
DISPLAY INVISIBLE (-4925 4850);
FORCEPROP 0 LAST PACK_TYPE C0201
J 2
(-5075 4850);
DISPLAY 0.680851 (-5075 4850);
DISPLAY INVISIBLE (-5075 4850);
FORCEADD TAP..6
(-5650 5000);
FORCEPROP 3 LASTPIN (-5600 5000) SIG_NAME P5E_CPU0_P0_TX_DP<8>
J 0
(-5590 5010);
DISPLAY 0.659574 (-5590 5010);
PAINT MONO (-5590 5010);
DISPLAY INVISIBLE (-5590 5010);
FORCEPROP 1 LASTPIN (-5600 5000) BN 8
J 0
(-5652 5008);
DISPLAY 0.680851 (-5652 5008);
PAINT MONO (-5652 5008);
FORCEPROP 2 LAST CDS_LIB standard
J 0
(-5650 5000);
DISPLAY INVISIBLE (-5650 5000);
FORCEPROP 1 LAST PATH I97
J 0
(-5652 5000);
DISPLAY 0.872340 (-5652 5000);
PAINT GREEN (-5652 5000);
DISPLAY INVISIBLE (-5652 5000);
FORCEPROP 1 LAST BODY_TYPE PLUMBING
J 0
(-5650 4950);
DISPLAY 0.574468 (-5650 4950);
PAINT GREEN (-5650 4950);
DISPLAY INVISIBLE (-5650 4950);
FORCEPROP 1 LAST HDL_TAP TRUE
J 0
(-5325 4875);
DISPLAY 0.574468 (-5325 4875);
PAINT GREEN (-5325 4875);
DISPLAY INVISIBLE (-5325 4875);
FORCEADD TAP..6
(-5650 5100);
FORCEPROP 3 LASTPIN (-5600 5100) SIG_NAME P5E_CPU0_P0_TX_DP<7>
J 0
(-5590 5110);
DISPLAY 0.659574 (-5590 5110);
PAINT MONO (-5590 5110);
DISPLAY INVISIBLE (-5590 5110);
FORCEPROP 1 LASTPIN (-5600 5100) BN 7
J 0
(-5652 5108);
DISPLAY 0.680851 (-5652 5108);
PAINT MONO (-5652 5108);
FORCEPROP 2 LAST CDS_LIB standard
J 0
(-5650 5100);
DISPLAY INVISIBLE (-5650 5100);
FORCEPROP 1 LAST PATH I98
J 0
(-5652 5100);
DISPLAY 0.872340 (-5652 5100);
PAINT GREEN (-5652 5100);
DISPLAY INVISIBLE (-5652 5100);
FORCEPROP 1 LAST BODY_TYPE PLUMBING
J 0
(-5650 5050);
DISPLAY 0.574468 (-5650 5050);
PAINT GREEN (-5650 5050);
DISPLAY INVISIBLE (-5650 5050);
FORCEPROP 1 LAST HDL_TAP TRUE
J 0
(-5325 4975);
DISPLAY 0.574468 (-5325 4975);
PAINT GREEN (-5325 4975);
DISPLAY INVISIBLE (-5325 4975);
FORCEADD TAP..6
(-5800 5250);
FORCEPROP 3 LASTPIN (-5750 5250) SIG_NAME P5E_CPU0_P0_TX_DN<5>
J 0
(-5740 5260);
DISPLAY 0.659574 (-5740 5260);
PAINT MONO (-5740 5260);
DISPLAY INVISIBLE (-5740 5260);
FORCEPROP 1 LASTPIN (-5750 5250) BN 5
J 0
(-5802 5258);
DISPLAY 0.680851 (-5802 5258);
PAINT MONO (-5802 5258);
FORCEPROP 2 LAST CDS_LIB standard
J 0
(-5800 5250);
DISPLAY INVISIBLE (-5800 5250);
FORCEPROP 1 LAST PATH I99
J 0
(-5802 5250);
DISPLAY 0.872340 (-5802 5250);
PAINT GREEN (-5802 5250);
DISPLAY INVISIBLE (-5802 5250);
FORCEPROP 1 LAST BODY_TYPE PLUMBING
J 0
(-5800 5200);
DISPLAY 0.574468 (-5800 5200);
PAINT GREEN (-5800 5200);
DISPLAY INVISIBLE (-5800 5200);
FORCEPROP 1 LAST HDL_TAP TRUE
J 0
(-5475 5125);
DISPLAY 0.574468 (-5475 5125);
PAINT GREEN (-5475 5125);
DISPLAY INVISIBLE (-5475 5125);
FORCEADD QUANTA_TITLE_BLOCK_C..1
(0 0);
FORCEPROP 0 LAST CDS_CON_LAST_MODIFIED Fri Mar 11 14:53:43 2022
J 0
(-1885 15);
DISPLAY INVISIBLE (-1885 15);
FORCEPROP 1 LAST CUSTOM_TXT_CDS <CON_LAST_MODIFIED>
J 0
(-1885 15);
DISPLAY 0.978723 (-1885 15);
FORCEPROP 2 LAST CUSTOM_TXT_CDS <XR_PAGE_TITLE>
J 0
(-7890 5250);
DISPLAY 0.638298 (-7890 5250);
PAINT PINK (-7890 5250);
DISPLAY INVISIBLE (-7890 5250);
FORCEPROP 1 LAST CUSTOM_TXT_CDS <NAME_2>
J 0
(-3175 50);
FORCEPROP 1 LAST CUSTOM_TXT_CDS <NAME_1>
J 0
(-3175 175);
FORCEPROP 1 LAST CUSTOM_TXT_CDS <Q_NUMBER>
J 0
(-1403 103);
DISPLAY 1.212766 (-1403 103);
FORCEPROP 1 LAST CUSTOM_TXT_CDS <Q_PROJ>
J 0
(-2382 102);
DISPLAY 1.212766 (-2382 102);
FORCEPROP 1 LAST CUSTOM_TXT_CDS <Q_REV>
J 0
(-184 103);
DISPLAY 1.212766 (-184 103);
FORCEPROP 1 LAST CUSTOM_TXT_CDS <CON_PAGE_NUM> OF <CON_TOTAL_PAGES>
J 0
(-446 18);
DISPLAY 0.978723 (-446 18);
FORCEPROP 1 LAST Q_DEPT BU9
J 1
(-3763 49);
DISPLAY 1.957447 (-3763 49);
PAINT GREEN (-3763 49);
FORCEPROP 1 LAST Q_TITLE AC CAPS CPU0 P0/P1 TX
J 0
(-9300 50);
DISPLAY 2.446809 (-9300 50);
PAINT GREEN (-9300 50);
FORCEPROP 2 LAST CDS_XR_PAGE_TITLE CR-63 : @T6G_MB_LIB.T6G(SCH_1):PAGE63
J 0
(-7890 5250);
DISPLAY 0.638298 (-7890 5250);
PAINT PINK (-7890 5250);
DISPLAY INVISIBLE (-7890 5250);
FORCEPROP 1 LAST COMMENT_BODY TRUE
J 0
(12 -13);
DISPLAY 0.978723 (12 -13);
PAINT GREEN (12 -13);
DISPLAY INVISIBLE (12 -13);
FORCEPROP 2 LAST CDS_LIB pure_quanta
J 0
(0 0);
DISPLAY INVISIBLE (0 0);
FORCEPROP 1 LAST CDS_LMAN_SYM_OUTLINE -9475,6775,100,-125
J 0
(0 0);
DISPLAY 0.468085 (0 0);
PAINT GREEN (0 0);
DISPLAY INVISIBLE (0 0);
FORCEPROP 2 LAST PAGE_BORDER TRUE
J 0
(-7890 5250);
DISPLAY 0.638298 (-7890 5250);
PAINT PINK (-7890 5250);
DISPLAY INVISIBLE (-7890 5250);
WIRE 17 -1 (-3725 1875)(-3725 1775);
WIRE 17 -1 (-3725 1975)(-3725 1875);
WIRE 17 -1 (-3725 2075)(-3725 1975);
WIRE 17 -1 (-3725 2175)(-3725 2075);
WIRE 17 -1 (-3725 2275)(-3725 2175);
WIRE 17 -1 (-3725 2375)(-3725 2275);
WIRE 17 -1 (-3725 2475)(-3725 2375);
WIRE 17 -1 (-3725 2575)(-3725 2475);
WIRE 17 -1 (-3725 2675)(-3725 2575);
WIRE 17 -1 (-3725 2775)(-3725 2675);
WIRE 17 -1 (-3725 2875)(-3725 2775);
WIRE 17 -1 (-3725 2975)(-3725 2875);
WIRE 17 -1 (-3725 3075)(-3725 2975);
WIRE 17 -1 (-3725 3175)(-3725 3075);
WIRE 17 -1 (-3725 3275)(-3725 3175);
WIRE 17 -1 (-3725 3475)(-3725 3275);
WIRE 17 -1 (-3725 3475)(-2850 3475);
FORCEPROP 2 LAST SIG_NAME P5E_CPU0_P1_TX_C_DN<15:0>
J 0
(-3735 3485);
DISPLAY 0.680851 (-3735 3485);
WIRE 17 -1 (-5700 5725)(-5700 5825);
WIRE 17 -1 (-5700 5625)(-5700 5725);
WIRE 17 -1 (-5700 5825)(-5700 6025);
WIRE 17 -1 (-5700 6025)(-6700 6025);
FORCEPROP 2 LAST SIG_NAME P5E_CPU0_P0_TX_DP<15:0>
J 0
(-6535 6035);
DISPLAY 0.680851 (-6535 6035);
WIRE 17 -1 (-5850 5675)(-5850 5775);
WIRE 17 -1 (-5850 5575)(-5850 5675);
WIRE 17 -1 (-5850 5775)(-5850 5975);
WIRE 17 -1 (-5850 5975)(-6700 5975);
FORCEPROP 2 LAST SIG_NAME P5E_CPU0_P0_TX_DN<15:0>
J 0
(-6535 5985);
DISPLAY 0.680851 (-6535 5985);
WIRE 17 -1 (-5700 5525)(-5700 5625);
WIRE 17 -1 (-5700 5425)(-5700 5525);
WIRE 17 -1 (-5700 5325)(-5700 5425);
WIRE 17 -1 (-5850 5375)(-5850 5475);
WIRE 17 -1 (-5850 5275)(-5850 5375);
WIRE 17 -1 (-5850 5475)(-5850 5575);
WIRE 17 -1 (-5850 5175)(-5850 5275);
WIRE 17 -1 (-5850 5075)(-5850 5175);
WIRE 17 -1 (-5850 4975)(-5850 5075);
WIRE 17 -1 (-5850 4875)(-5850 4975);
WIRE 17 -1 (-3875 6025)(-3875 5825);
WIRE 17 -1 (-3875 6025)(-2850 6025);
FORCEPROP 2 LAST SIG_NAME P5E_CPU0_P0_TX_C_DP<15:0>
J 0
(-3785 6060);
DISPLAY 0.680851 (-3785 6060);
WIRE 17 -1 (-3725 5975)(-3725 5775);
WIRE 17 -1 (-3725 5975)(-2850 5975);
FORCEPROP 2 LAST SIG_NAME P5E_CPU0_P0_TX_C_DN<15:0>
J 0
(-3785 5985);
DISPLAY 0.680851 (-3785 5985);
WIRE 17 -1 (-3875 5425)(-3875 5325);
WIRE 17 -1 (-3875 5525)(-3875 5425);
WIRE 17 -1 (-3875 5325)(-3875 5225);
WIRE 17 -1 (-3875 5225)(-3875 5125);
WIRE 17 -1 (-3875 5625)(-3875 5525);
WIRE 17 -1 (-3875 5725)(-3875 5625);
WIRE 17 -1 (-3875 5125)(-3875 5025);
WIRE 17 -1 (-3875 5025)(-3875 4925);
WIRE 17 -1 (-3875 5825)(-3875 5725);
WIRE 17 -1 (-3875 4925)(-3875 4825);
WIRE 17 -1 (-3875 4825)(-3875 4725);
WIRE 17 -1 (-5700 5025)(-5700 5125);
WIRE 17 -1 (-5700 4925)(-5700 5025);
WIRE 17 -1 (-5700 5125)(-5700 5225);
WIRE 17 -1 (-5700 5225)(-5700 5325);
WIRE 17 -1 (-5700 4825)(-5700 4925);
WIRE 17 -1 (-5700 4725)(-5700 4825);
WIRE 17 -1 (-5700 4625)(-5700 4725);
WIRE 17 -1 (-5700 4525)(-5700 4625);
WIRE 17 -1 (-5700 4425)(-5700 4525);
WIRE 17 -1 (-5700 4325)(-5700 4425);
WIRE 17 -1 (-5850 4675)(-5850 4775);
WIRE 17 -1 (-5850 4575)(-5850 4675);
WIRE 17 -1 (-5850 4775)(-5850 4875);
WIRE 17 -1 (-5850 4475)(-5850 4575);
WIRE 17 -1 (-5850 4375)(-5850 4475);
WIRE 17 -1 (-5850 4275)(-5850 4375);
WIRE 17 -1 (-5700 3225)(-5700 3325);
WIRE 17 -1 (-5700 3125)(-5700 3225);
WIRE 17 -1 (-5700 3325)(-5700 3525);
WIRE 17 -1 (-5700 3525)(-6700 3525);
FORCEPROP 2 LAST SIG_NAME P5E_CPU0_P1_TX_DP<15:0>
J 0
(-6660 3560);
DISPLAY 0.680851 (-6660 3560);
WIRE 17 -1 (-3875 3125)(-3875 3025);
WIRE 17 -1 (-3875 3225)(-3875 3125);
WIRE 17 -1 (-3875 3025)(-3875 2925);
WIRE 17 -1 (-3875 2925)(-3875 2825);
WIRE 17 -1 (-3875 3325)(-3875 3225);
WIRE 17 -1 (-3875 3525)(-3875 3325);
WIRE 17 -1 (-3875 2825)(-3875 2725);
WIRE 17 -1 (-3875 2725)(-3875 2625);
WIRE 17 -1 (-3875 3525)(-2850 3525);
FORCEPROP 2 LAST SIG_NAME P5E_CPU0_P1_TX_C_DP<15:0>
J 0
(-3735 3560);
DISPLAY 0.680851 (-3735 3560);
WIRE 17 -1 (-3875 2625)(-3875 2525);
WIRE 17 -1 (-3875 2525)(-3875 2425);
WIRE 17 -1 (-3875 2425)(-3875 2325);
WIRE 17 -1 (-3875 2325)(-3875 2225);
WIRE 17 -1 (-3875 2225)(-3875 2125);
WIRE 17 -1 (-3875 2125)(-3875 2025);
WIRE 17 -1 (-3875 2025)(-3875 1925);
WIRE 17 -1 (-3875 1925)(-3875 1825);
WIRE 17 -1 (-5850 3175)(-5850 3275);
WIRE 17 -1 (-5850 3075)(-5850 3175);
WIRE 17 -1 (-5850 3275)(-5850 3475);
WIRE 17 -1 (-5850 3475)(-6700 3475);
FORCEPROP 2 LAST SIG_NAME P5E_CPU0_P1_TX_DN<15:0>
J 0
(-6660 3485);
DISPLAY 0.680851 (-6660 3485);
WIRE 17 -1 (-5700 3025)(-5700 3125);
WIRE 17 -1 (-5700 2925)(-5700 3025);
WIRE 17 -1 (-5700 2825)(-5700 2925);
WIRE 17 -1 (-5700 2725)(-5700 2825);
WIRE 17 -1 (-5850 2675)(-5850 2775);
WIRE 17 -1 (-5850 2575)(-5850 2675);
WIRE 17 -1 (-5850 2775)(-5850 2875);
WIRE 17 -1 (-5850 2875)(-5850 2975);
WIRE 17 -1 (-5850 2475)(-5850 2575);
WIRE 17 -1 (-5850 2375)(-5850 2475);
WIRE 17 -1 (-5850 2975)(-5850 3075);
WIRE 17 -1 (-5850 2275)(-5850 2375);
WIRE 17 -1 (-5850 2175)(-5850 2275);
WIRE 17 -1 (-5850 2075)(-5850 2175);
WIRE 17 -1 (-5850 1975)(-5850 2075);
WIRE 17 -1 (-5850 1875)(-5850 1975);
WIRE 17 -1 (-5700 2625)(-5700 2725);
WIRE 17 -1 (-5700 2525)(-5700 2625);
WIRE 17 -1 (-5700 2425)(-5700 2525);
WIRE 17 -1 (-5700 2325)(-5700 2425);
WIRE 17 -1 (-5700 2225)(-5700 2325);
WIRE 17 -1 (-5700 2125)(-5700 2225);
WIRE 17 -1 (-5700 2025)(-5700 2125);
WIRE 17 -1 (-5700 1925)(-5700 2025);
WIRE 17 -1 (-5700 1825)(-5700 1925);
WIRE 17 -1 (-5850 1775)(-5850 1875);
WIRE 17 -1 (-3725 5675)(-3725 5575);
WIRE 17 -1 (-3725 5775)(-3725 5675);
WIRE 17 -1 (-3725 5575)(-3725 5475);
WIRE 17 -1 (-3725 5475)(-3725 5375);
WIRE 17 -1 (-3725 5375)(-3725 5275);
WIRE 17 -1 (-3725 5275)(-3725 5175);
WIRE 17 -1 (-3725 5175)(-3725 5075);
WIRE 17 -1 (-3725 5075)(-3725 4975);
WIRE 17 -1 (-3875 4725)(-3875 4625);
WIRE 17 -1 (-3875 4625)(-3875 4525);
WIRE 17 -1 (-3875 4525)(-3875 4425);
WIRE 17 -1 (-3875 4425)(-3875 4325);
WIRE 17 -1 (-3725 4975)(-3725 4875);
WIRE 17 -1 (-3725 4875)(-3725 4775);
WIRE 17 -1 (-3725 4775)(-3725 4675);
WIRE 17 -1 (-3725 4675)(-3725 4575);
WIRE 17 -1 (-3725 4575)(-3725 4475);
WIRE 17 -1 (-3725 4475)(-3725 4375);
WIRE 17 -1 (-3725 4375)(-3725 4275);
WIRE 16 -1 (-5000 5250)(-5750 5250);
WIRE 16 -1 (-5000 5300)(-5600 5300);
WIRE 16 -1 (-3975 5400)(-4850 5400);
WIRE 16 -1 (-3825 5350)(-4850 5350);
WIRE 16 -1 (-5000 5200)(-5600 5200);
WIRE 16 -1 (-5000 5150)(-5750 5150);
WIRE 16 -1 (-5000 5050)(-5750 5050);
WIRE 16 -1 (-5000 5000)(-5600 5000);
WIRE 16 -1 (-5000 4950)(-5750 4950);
WIRE 16 -1 (-5000 5650)(-5750 5650);
WIRE 16 -1 (-5000 5600)(-5600 5600);
WIRE 16 -1 (-5000 5400)(-5600 5400);
WIRE 16 -1 (-5000 5350)(-5750 5350);
WIRE 16 -1 (-3825 5050)(-4850 5050);
WIRE 16 -1 (-3825 5150)(-4850 5150);
WIRE 16 -1 (-3825 5250)(-4850 5250);
WIRE 16 -1 (-3825 4250)(-4850 4250);
WIRE 16 -1 (-3975 4300)(-4850 4300);
WIRE 16 -1 (-3825 4350)(-4850 4350);
WIRE 16 -1 (-3975 4400)(-4850 4400);
WIRE 16 -1 (-3825 4450)(-4850 4450);
WIRE 16 -1 (-3975 4500)(-4850 4500);
WIRE 16 -1 (-3825 4550)(-4850 4550);
WIRE 16 -1 (-3975 4600)(-4850 4600);
WIRE 16 -1 (-3825 4650)(-4850 4650);
WIRE 16 -1 (-3975 4700)(-4850 4700);
WIRE 16 -1 (-3825 4750)(-4850 4750);
WIRE 16 -1 (-3975 4800)(-4850 4800);
WIRE 16 -1 (-3825 4850)(-4850 4850);
WIRE 16 -1 (-3975 4900)(-4850 4900);
WIRE 16 -1 (-3825 4950)(-4850 4950);
WIRE 16 -1 (-3975 5000)(-4850 5000);
WIRE 16 -1 (-3975 5100)(-4850 5100);
WIRE 16 -1 (-3975 5200)(-4850 5200);
WIRE 16 -1 (-3825 5450)(-4850 5450);
WIRE 16 -1 (-3975 5500)(-4850 5500);
WIRE 16 -1 (-3825 5550)(-4850 5550);
WIRE 16 -1 (-3975 5600)(-4850 5600);
WIRE 16 -1 (-3825 5650)(-4850 5650);
WIRE 16 -1 (-3975 5700)(-4850 5700);
WIRE 16 -1 (-5000 1850)(-5750 1850);
WIRE 16 -1 (-5000 1800)(-5600 1800);
WIRE 16 -1 (-5000 1750)(-5750 1750);
WIRE 16 -1 (-5000 1900)(-5600 1900);
WIRE 16 -1 (-5000 2150)(-5750 2150);
WIRE 16 -1 (-5000 1950)(-5750 1950);
WIRE 16 -1 (-5000 2000)(-5600 2000);
WIRE 16 -1 (-5000 2050)(-5750 2050);
WIRE 16 -1 (-3975 1800)(-4850 1800);
WIRE 16 -1 (-3975 2000)(-4850 2000);
WIRE 16 -1 (-3825 2050)(-4850 2050);
WIRE 16 -1 (-5000 2100)(-5600 2100);
WIRE 16 -1 (-5000 2200)(-5600 2200);
WIRE 16 -1 (-5000 2250)(-5750 2250);
WIRE 16 -1 (-5000 2300)(-5600 2300);
WIRE 16 -1 (-5000 2350)(-5750 2350);
WIRE 16 -1 (-3825 1950)(-4850 1950);
WIRE 16 -1 (-3975 1900)(-4850 1900);
WIRE 16 -1 (-3825 1850)(-4850 1850);
WIRE 16 -1 (-3975 2100)(-4850 2100);
WIRE 16 -1 (-3825 2150)(-4850 2150);
WIRE 16 -1 (-3975 2200)(-4850 2200);
WIRE 16 -1 (-3825 2250)(-4850 2250);
WIRE 16 -1 (-3975 2300)(-4850 2300);
WIRE 16 -1 (-3825 2350)(-4850 2350);
WIRE 16 -1 (-3975 2400)(-4850 2400);
WIRE 16 -1 (-5000 2450)(-5750 2450);
WIRE 16 -1 (-5000 2500)(-5600 2500);
WIRE 16 -1 (-5000 2550)(-5750 2550);
WIRE 16 -1 (-5000 2400)(-5600 2400);
WIRE 16 -1 (-5000 2600)(-5600 2600);
WIRE 16 -1 (-3825 2550)(-4850 2550);
WIRE 16 -1 (-5000 2850)(-5750 2850);
WIRE 16 -1 (-5000 2900)(-5600 2900);
WIRE 16 -1 (-5000 2950)(-5750 2950);
WIRE 16 -1 (-5000 3000)(-5600 3000);
WIRE 16 -1 (-5000 2700)(-5600 2700);
WIRE 16 -1 (-5000 3050)(-5750 3050);
WIRE 16 -1 (-5000 3150)(-5750 3150);
WIRE 16 -1 (-5000 2800)(-5600 2800);
WIRE 16 -1 (-5000 2650)(-5750 2650);
WIRE 16 -1 (-5000 2750)(-5750 2750);
WIRE 16 -1 (-5000 3100)(-5600 3100);
WIRE 16 -1 (-5000 3200)(-5600 3200);
WIRE 16 -1 (-5750 3250)(-5000 3250);
WIRE 16 -1 (-3975 3300)(-4850 3300);
WIRE 16 -1 (-3975 2900)(-4850 2900);
WIRE 16 -1 (-3825 2950)(-4850 2950);
WIRE 16 -1 (-3975 3000)(-4850 3000);
WIRE 16 -1 (-3825 3050)(-4850 3050);
WIRE 16 -1 (-3825 3150)(-4850 3150);
WIRE 16 -1 (-3975 3200)(-4850 3200);
WIRE 16 -1 (-3975 2800)(-4850 2800);
WIRE 16 -1 (-3825 2750)(-4850 2750);
WIRE 16 -1 (-3975 2700)(-4850 2700);
WIRE 16 -1 (-3825 2650)(-4850 2650);
WIRE 16 -1 (-3975 2600)(-4850 2600);
WIRE 16 -1 (-3975 2500)(-4850 2500);
WIRE 16 -1 (-3825 2450)(-4850 2450);
WIRE 16 -1 (-3975 3100)(-4850 3100);
WIRE 16 -1 (-3825 3250)(-4850 3250);
WIRE 16 -1 (-5600 3300)(-5000 3300);
WIRE 16 -1 (-5000 5500)(-5600 5500);
WIRE 16 -1 (-5000 5550)(-5750 5550);
WIRE 16 -1 (-5000 4450)(-5750 4450);
WIRE 16 -1 (-5000 4300)(-5600 4300);
WIRE 16 -1 (-5000 4250)(-5750 4250);
WIRE 16 -1 (-5000 4350)(-5750 4350);
WIRE 16 -1 (-5000 4400)(-5600 4400);
WIRE 16 -1 (-5000 4650)(-5750 4650);
WIRE 16 -1 (-5000 4600)(-5600 4600);
WIRE 16 -1 (-5000 4550)(-5750 4550);
WIRE 16 -1 (-5000 4850)(-5750 4850);
WIRE 16 -1 (-5000 4800)(-5600 4800);
WIRE 16 -1 (-5000 4750)(-5750 4750);
WIRE 16 -1 (-5000 4500)(-5600 4500);
WIRE 16 -1 (-5000 4700)(-5600 4700);
WIRE 16 -1 (-5000 4900)(-5600 4900);
WIRE 16 -1 (-5000 5100)(-5600 5100);
WIRE 16 -1 (-3975 5300)(-4850 5300);
WIRE 16 -1 (-3825 5750)(-4850 5750);
WIRE 16 -1 (-3975 5800)(-4850 5800);
WIRE 16 -1 (-5000 5450)(-5750 5450);
WIRE 16 -1 (-5000 5700)(-5600 5700);
WIRE 16 -1 (-5750 5750)(-5000 5750);
WIRE 16 -1 (-3825 2850)(-4850 2850);
WIRE 16 -1 (-5600 5800)(-5000 5800);
WIRE 16 -1 (-3825 1750)(-4850 1750);
FORCENOTE
CPU0 P1[15:0] TO EXAMAX
(-2875 2675) 0;
DISPLAY LEFT (-2875 2675);
DISPLAY 2.000000 (-2875 2675);
FORCENOTE
CPU0 P0[15:0] TO EXAMAX
(-2875 5175) 0;
DISPLAY LEFT (-2875 5175);
DISPLAY 2.000000 (-2875 5175);
QUIT
